FILE_TYPE = MACRO_DRAWING;
SET COLOR_WIRE YELLOW;
SET COLOR_PROP ORANGE;
SET COLOR_DOT WHITE;
SET COLOR_ARC YELLOW;
SET COLOR_BODY GREEN;
SET COLOR_NOTE PURPLE;
SET PROP_DISPLAY VALUE;
SET PAGE_NUMBER P95;
FORCEADD OFFPAGE..6
(-8325 3575);
FORCEPROP 2 LAST $XR0 20 
J 0
(-8574 3575);
DISPLAY 0.638298 (-8574 3575);
PAINT MONO (-8574 3575);
FORCEPROP 2 LAST PATH I10
J 0
(-8275 3650);
DISPLAY 1.021277 (-8275 3650);
DISPLAY INVISIBLE (-8275 3650);
FORCEPROP 1 LAST COMMENT_BODY TRUE
J 0
(-8225 3500);
DISPLAY 0.872340 (-8225 3500);
PAINT GREEN (-8225 3500);
DISPLAY INVISIBLE (-8225 3500);
FORCEPROP 1 LAST OFFPAGE TRUE
J 0
(-8000 3450);
DISPLAY 0.872340 (-8000 3450);
PAINT GREEN (-8000 3450);
DISPLAY INVISIBLE (-8000 3450);
FORCEPROP 2 LAST CDS_LIB mstr_standard
J 0
(-8325 3575);
DISPLAY 0.723404 (-8325 3575);
PAINT MONO (-8325 3575);
DISPLAY INVISIBLE (-8325 3575);
FORCEADD TAP..1
(-6025 4125);
FORCEPROP 3 LASTPIN (-6075 4125) SIG_NAME M_K_CPU0_SA_DQ<6>
J 0
(-6065 4135);
DISPLAY 0.659574 (-6065 4135);
PAINT MONO (-6065 4135);
DISPLAY INVISIBLE (-6065 4135);
FORCEPROP 1 LASTPIN (-6075 4125) BN 6
J 0
(-6087 4133);
DISPLAY 0.489362 (-6087 4133);
PAINT GREEN (-6087 4133);
FORCEPROP 2 LAST CDS_LIB mstr_standard
J 0
(-6025 4125);
DISPLAY 0.723404 (-6025 4125);
PAINT MONO (-6025 4125);
DISPLAY INVISIBLE (-6025 4125);
FORCEPROP 1 LAST BODY_TYPE PLUMBING
J 0
(-6025 4175);
DISPLAY 0.872340 (-6025 4175);
PAINT GREEN (-6025 4175);
DISPLAY INVISIBLE (-6025 4175);
FORCEPROP 1 LAST HDL_TAP TRUE
J 0
(-5700 4000);
DISPLAY 0.872340 (-5700 4000);
DISPLAY INVISIBLE (-5700 4000);
FORCEPROP 1 LAST PATH I100
J 0
(-6027 4125);
DISPLAY 0.872340 (-6027 4125);
PAINT GREEN (-6027 4125);
DISPLAY INVISIBLE (-6027 4125);
FORCEADD TAP..1
(-6025 4175);
FORCEPROP 3 LASTPIN (-6075 4175) SIG_NAME M_K_CPU0_SA_DQ<7>
J 0
(-6065 4185);
DISPLAY 0.659574 (-6065 4185);
PAINT MONO (-6065 4185);
DISPLAY INVISIBLE (-6065 4185);
FORCEPROP 1 LASTPIN (-6075 4175) BN 7
J 0
(-6087 4183);
DISPLAY 0.489362 (-6087 4183);
PAINT GREEN (-6087 4183);
FORCEPROP 2 LAST CDS_LIB mstr_standard
J 0
(-6025 4175);
DISPLAY 0.723404 (-6025 4175);
PAINT MONO (-6025 4175);
DISPLAY INVISIBLE (-6025 4175);
FORCEPROP 1 LAST BODY_TYPE PLUMBING
J 0
(-6025 4225);
DISPLAY 0.872340 (-6025 4225);
PAINT GREEN (-6025 4225);
DISPLAY INVISIBLE (-6025 4225);
FORCEPROP 1 LAST HDL_TAP TRUE
J 0
(-5700 4050);
DISPLAY 0.872340 (-5700 4050);
DISPLAY INVISIBLE (-5700 4050);
FORCEPROP 1 LAST PATH I101
J 0
(-6027 4175);
DISPLAY 0.872340 (-6027 4175);
PAINT GREEN (-6027 4175);
DISPLAY INVISIBLE (-6027 4175);
FORCEADD TAP..1
(-6025 4225);
FORCEPROP 3 LASTPIN (-6075 4225) SIG_NAME M_K_CPU0_SA_DQ<8>
J 0
(-6065 4235);
DISPLAY 0.659574 (-6065 4235);
PAINT MONO (-6065 4235);
DISPLAY INVISIBLE (-6065 4235);
FORCEPROP 1 LASTPIN (-6075 4225) BN 8
J 0
(-6087 4233);
DISPLAY 0.489362 (-6087 4233);
PAINT GREEN (-6087 4233);
FORCEPROP 2 LAST CDS_LIB mstr_standard
J 0
(-6025 4225);
DISPLAY 0.723404 (-6025 4225);
PAINT MONO (-6025 4225);
DISPLAY INVISIBLE (-6025 4225);
FORCEPROP 1 LAST BODY_TYPE PLUMBING
J 0
(-6025 4275);
DISPLAY 0.872340 (-6025 4275);
PAINT GREEN (-6025 4275);
DISPLAY INVISIBLE (-6025 4275);
FORCEPROP 1 LAST HDL_TAP TRUE
J 0
(-5700 4100);
DISPLAY 0.872340 (-5700 4100);
DISPLAY INVISIBLE (-5700 4100);
FORCEPROP 1 LAST PATH I102
J 0
(-6027 4225);
DISPLAY 0.872340 (-6027 4225);
PAINT GREEN (-6027 4225);
DISPLAY INVISIBLE (-6027 4225);
FORCEADD TAP..1
(-6025 4275);
FORCEPROP 3 LASTPIN (-6075 4275) SIG_NAME M_K_CPU0_SA_DQ<9>
J 0
(-6065 4285);
DISPLAY 0.659574 (-6065 4285);
PAINT MONO (-6065 4285);
DISPLAY INVISIBLE (-6065 4285);
FORCEPROP 1 LASTPIN (-6075 4275) BN 9
J 0
(-6087 4283);
DISPLAY 0.489362 (-6087 4283);
PAINT GREEN (-6087 4283);
FORCEPROP 2 LAST CDS_LIB mstr_standard
J 0
(-6025 4275);
DISPLAY 0.723404 (-6025 4275);
PAINT MONO (-6025 4275);
DISPLAY INVISIBLE (-6025 4275);
FORCEPROP 1 LAST BODY_TYPE PLUMBING
J 0
(-6025 4325);
DISPLAY 0.872340 (-6025 4325);
PAINT GREEN (-6025 4325);
DISPLAY INVISIBLE (-6025 4325);
FORCEPROP 1 LAST HDL_TAP TRUE
J 0
(-5700 4150);
DISPLAY 0.872340 (-5700 4150);
DISPLAY INVISIBLE (-5700 4150);
FORCEPROP 1 LAST PATH I103
J 0
(-6027 4275);
DISPLAY 0.872340 (-6027 4275);
PAINT GREEN (-6027 4275);
DISPLAY INVISIBLE (-6027 4275);
FORCEADD TAP..1
(-6025 4325);
FORCEPROP 3 LASTPIN (-6075 4325) SIG_NAME M_K_CPU0_SA_DQ<10>
J 0
(-6065 4335);
DISPLAY 0.659574 (-6065 4335);
PAINT MONO (-6065 4335);
DISPLAY INVISIBLE (-6065 4335);
FORCEPROP 1 LASTPIN (-6075 4325) BN 10
J 0
(-6087 4333);
DISPLAY 0.489362 (-6087 4333);
PAINT GREEN (-6087 4333);
FORCEPROP 2 LAST CDS_LIB mstr_standard
J 0
(-6025 4325);
DISPLAY 0.723404 (-6025 4325);
PAINT MONO (-6025 4325);
DISPLAY INVISIBLE (-6025 4325);
FORCEPROP 1 LAST BODY_TYPE PLUMBING
J 0
(-6025 4375);
DISPLAY 0.872340 (-6025 4375);
PAINT GREEN (-6025 4375);
DISPLAY INVISIBLE (-6025 4375);
FORCEPROP 1 LAST HDL_TAP TRUE
J 0
(-5700 4200);
DISPLAY 0.872340 (-5700 4200);
DISPLAY INVISIBLE (-5700 4200);
FORCEPROP 1 LAST PATH I104
J 0
(-6027 4325);
DISPLAY 0.872340 (-6027 4325);
PAINT GREEN (-6027 4325);
DISPLAY INVISIBLE (-6027 4325);
FORCEADD TAP..1
(-6025 4425);
FORCEPROP 3 LASTPIN (-6075 4425) SIG_NAME M_K_CPU0_SA_DQ<12>
J 0
(-6065 4435);
DISPLAY 0.659574 (-6065 4435);
PAINT MONO (-6065 4435);
DISPLAY INVISIBLE (-6065 4435);
FORCEPROP 1 LASTPIN (-6075 4425) BN 12
J 0
(-6087 4433);
DISPLAY 0.489362 (-6087 4433);
PAINT GREEN (-6087 4433);
FORCEPROP 2 LAST CDS_LIB mstr_standard
J 0
(-6025 4425);
DISPLAY 0.723404 (-6025 4425);
PAINT MONO (-6025 4425);
DISPLAY INVISIBLE (-6025 4425);
FORCEPROP 1 LAST BODY_TYPE PLUMBING
J 0
(-6025 4475);
DISPLAY 0.872340 (-6025 4475);
PAINT GREEN (-6025 4475);
DISPLAY INVISIBLE (-6025 4475);
FORCEPROP 1 LAST HDL_TAP TRUE
J 0
(-5700 4300);
DISPLAY 0.872340 (-5700 4300);
DISPLAY INVISIBLE (-5700 4300);
FORCEPROP 1 LAST PATH I105
J 0
(-6027 4425);
DISPLAY 0.872340 (-6027 4425);
PAINT GREEN (-6027 4425);
DISPLAY INVISIBLE (-6027 4425);
FORCEADD TAP..1
(-6025 4375);
FORCEPROP 3 LASTPIN (-6075 4375) SIG_NAME M_K_CPU0_SA_DQ<11>
J 0
(-6065 4385);
DISPLAY 0.659574 (-6065 4385);
PAINT MONO (-6065 4385);
DISPLAY INVISIBLE (-6065 4385);
FORCEPROP 1 LASTPIN (-6075 4375) BN 11
J 0
(-6087 4383);
DISPLAY 0.489362 (-6087 4383);
PAINT GREEN (-6087 4383);
FORCEPROP 2 LAST CDS_LIB mstr_standard
J 0
(-6025 4375);
DISPLAY 0.723404 (-6025 4375);
PAINT MONO (-6025 4375);
DISPLAY INVISIBLE (-6025 4375);
FORCEPROP 1 LAST BODY_TYPE PLUMBING
J 0
(-6025 4425);
DISPLAY 0.872340 (-6025 4425);
PAINT GREEN (-6025 4425);
DISPLAY INVISIBLE (-6025 4425);
FORCEPROP 1 LAST HDL_TAP TRUE
J 0
(-5700 4250);
DISPLAY 0.872340 (-5700 4250);
DISPLAY INVISIBLE (-5700 4250);
FORCEPROP 1 LAST PATH I106
J 0
(-6027 4375);
DISPLAY 0.872340 (-6027 4375);
PAINT GREEN (-6027 4375);
DISPLAY INVISIBLE (-6027 4375);
FORCEADD TAP..1
(-6025 4475);
FORCEPROP 3 LASTPIN (-6075 4475) SIG_NAME M_K_CPU0_SA_DQ<13>
J 0
(-6065 4485);
DISPLAY 0.659574 (-6065 4485);
PAINT MONO (-6065 4485);
DISPLAY INVISIBLE (-6065 4485);
FORCEPROP 1 LASTPIN (-6075 4475) BN 13
J 0
(-6087 4483);
DISPLAY 0.489362 (-6087 4483);
PAINT GREEN (-6087 4483);
FORCEPROP 2 LAST CDS_LIB mstr_standard
J 0
(-6025 4475);
DISPLAY 0.723404 (-6025 4475);
PAINT MONO (-6025 4475);
DISPLAY INVISIBLE (-6025 4475);
FORCEPROP 1 LAST BODY_TYPE PLUMBING
J 0
(-6025 4525);
DISPLAY 0.872340 (-6025 4525);
PAINT GREEN (-6025 4525);
DISPLAY INVISIBLE (-6025 4525);
FORCEPROP 1 LAST HDL_TAP TRUE
J 0
(-5700 4350);
DISPLAY 0.872340 (-5700 4350);
DISPLAY INVISIBLE (-5700 4350);
FORCEPROP 1 LAST PATH I107
J 0
(-6027 4475);
DISPLAY 0.872340 (-6027 4475);
PAINT GREEN (-6027 4475);
DISPLAY INVISIBLE (-6027 4475);
FORCEADD TAP..1
(-6025 4525);
FORCEPROP 3 LASTPIN (-6075 4525) SIG_NAME M_K_CPU0_SA_DQ<14>
J 0
(-6065 4535);
DISPLAY 0.659574 (-6065 4535);
PAINT MONO (-6065 4535);
DISPLAY INVISIBLE (-6065 4535);
FORCEPROP 1 LASTPIN (-6075 4525) BN 14
J 0
(-6087 4533);
DISPLAY 0.489362 (-6087 4533);
PAINT GREEN (-6087 4533);
FORCEPROP 2 LAST CDS_LIB mstr_standard
J 0
(-6025 4525);
DISPLAY 0.723404 (-6025 4525);
PAINT MONO (-6025 4525);
DISPLAY INVISIBLE (-6025 4525);
FORCEPROP 1 LAST BODY_TYPE PLUMBING
J 0
(-6025 4575);
DISPLAY 0.872340 (-6025 4575);
PAINT GREEN (-6025 4575);
DISPLAY INVISIBLE (-6025 4575);
FORCEPROP 1 LAST HDL_TAP TRUE
J 0
(-5700 4400);
DISPLAY 0.872340 (-5700 4400);
DISPLAY INVISIBLE (-5700 4400);
FORCEPROP 1 LAST PATH I108
J 0
(-6027 4525);
DISPLAY 0.872340 (-6027 4525);
PAINT GREEN (-6027 4525);
DISPLAY INVISIBLE (-6027 4525);
FORCEADD TAP..1
(-6025 4575);
FORCEPROP 3 LASTPIN (-6075 4575) SIG_NAME M_K_CPU0_SA_DQ<15>
J 0
(-6065 4585);
DISPLAY 0.659574 (-6065 4585);
PAINT MONO (-6065 4585);
DISPLAY INVISIBLE (-6065 4585);
FORCEPROP 1 LASTPIN (-6075 4575) BN 15
J 0
(-6087 4583);
DISPLAY 0.489362 (-6087 4583);
PAINT GREEN (-6087 4583);
FORCEPROP 2 LAST CDS_LIB mstr_standard
J 0
(-6025 4575);
DISPLAY 0.723404 (-6025 4575);
PAINT MONO (-6025 4575);
DISPLAY INVISIBLE (-6025 4575);
FORCEPROP 1 LAST BODY_TYPE PLUMBING
J 0
(-6025 4625);
DISPLAY 0.872340 (-6025 4625);
PAINT GREEN (-6025 4625);
DISPLAY INVISIBLE (-6025 4625);
FORCEPROP 1 LAST HDL_TAP TRUE
J 0
(-5700 4450);
DISPLAY 0.872340 (-5700 4450);
DISPLAY INVISIBLE (-5700 4450);
FORCEPROP 1 LAST PATH I109
J 0
(-6027 4575);
DISPLAY 0.872340 (-6027 4575);
PAINT GREEN (-6027 4575);
DISPLAY INVISIBLE (-6027 4575);
FORCEADD OFFPAGE..1
(-8325 4125);
FORCEPROP 2 LAST $XR0 20 
J 0
(-8546 4125);
DISPLAY 0.638298 (-8546 4125);
PAINT MONO (-8546 4125);
FORCEPROP 2 LAST PATH I11
J 0
(-8275 4200);
DISPLAY 1.021277 (-8275 4200);
DISPLAY INVISIBLE (-8275 4200);
FORCEPROP 1 LAST COMMENT_BODY TRUE
J 0
(-8200 4025);
DISPLAY 0.872340 (-8200 4025);
PAINT GREEN (-8200 4025);
DISPLAY INVISIBLE (-8200 4025);
FORCEPROP 1 LAST OFFPAGE TRUE
J 0
(-8000 4000);
DISPLAY 0.872340 (-8000 4000);
PAINT GREEN (-8000 4000);
DISPLAY INVISIBLE (-8000 4000);
FORCEPROP 2 LAST CDS_LIB mstr_standard
J 0
(-8325 4125);
DISPLAY 0.723404 (-8325 4125);
PAINT MONO (-8325 4125);
DISPLAY INVISIBLE (-8325 4125);
FORCEADD TAP..1
(-6025 4625);
FORCEPROP 3 LASTPIN (-6075 4625) SIG_NAME M_K_CPU0_SA_DQ<16>
J 0
(-6065 4635);
DISPLAY 0.659574 (-6065 4635);
PAINT MONO (-6065 4635);
DISPLAY INVISIBLE (-6065 4635);
FORCEPROP 1 LASTPIN (-6075 4625) BN 16
J 0
(-6087 4633);
DISPLAY 0.489362 (-6087 4633);
PAINT GREEN (-6087 4633);
FORCEPROP 2 LAST CDS_LIB mstr_standard
J 0
(-6025 4625);
DISPLAY 0.723404 (-6025 4625);
PAINT MONO (-6025 4625);
DISPLAY INVISIBLE (-6025 4625);
FORCEPROP 1 LAST BODY_TYPE PLUMBING
J 0
(-6025 4675);
DISPLAY 0.872340 (-6025 4675);
PAINT GREEN (-6025 4675);
DISPLAY INVISIBLE (-6025 4675);
FORCEPROP 1 LAST HDL_TAP TRUE
J 0
(-5700 4500);
DISPLAY 0.872340 (-5700 4500);
DISPLAY INVISIBLE (-5700 4500);
FORCEPROP 1 LAST PATH I110
J 0
(-6027 4625);
DISPLAY 0.872340 (-6027 4625);
PAINT GREEN (-6027 4625);
DISPLAY INVISIBLE (-6027 4625);
FORCEADD TAP..1
(-6025 4675);
FORCEPROP 3 LASTPIN (-6075 4675) SIG_NAME M_K_CPU0_SA_DQ<17>
J 0
(-6065 4685);
DISPLAY 0.659574 (-6065 4685);
PAINT MONO (-6065 4685);
DISPLAY INVISIBLE (-6065 4685);
FORCEPROP 1 LASTPIN (-6075 4675) BN 17
J 0
(-6087 4683);
DISPLAY 0.489362 (-6087 4683);
PAINT GREEN (-6087 4683);
FORCEPROP 2 LAST CDS_LIB mstr_standard
J 0
(-6025 4675);
DISPLAY 0.723404 (-6025 4675);
PAINT MONO (-6025 4675);
DISPLAY INVISIBLE (-6025 4675);
FORCEPROP 1 LAST BODY_TYPE PLUMBING
J 0
(-6025 4725);
DISPLAY 0.872340 (-6025 4725);
PAINT GREEN (-6025 4725);
DISPLAY INVISIBLE (-6025 4725);
FORCEPROP 1 LAST HDL_TAP TRUE
J 0
(-5700 4550);
DISPLAY 0.872340 (-5700 4550);
DISPLAY INVISIBLE (-5700 4550);
FORCEPROP 1 LAST PATH I111
J 0
(-6027 4675);
DISPLAY 0.872340 (-6027 4675);
PAINT GREEN (-6027 4675);
DISPLAY INVISIBLE (-6027 4675);
FORCEADD TAP..1
(-6025 4725);
FORCEPROP 3 LASTPIN (-6075 4725) SIG_NAME M_K_CPU0_SA_DQ<18>
J 0
(-6065 4735);
DISPLAY 0.659574 (-6065 4735);
PAINT MONO (-6065 4735);
DISPLAY INVISIBLE (-6065 4735);
FORCEPROP 1 LASTPIN (-6075 4725) BN 18
J 0
(-6087 4733);
DISPLAY 0.489362 (-6087 4733);
PAINT GREEN (-6087 4733);
FORCEPROP 2 LAST CDS_LIB mstr_standard
J 0
(-6025 4725);
DISPLAY 0.723404 (-6025 4725);
PAINT MONO (-6025 4725);
DISPLAY INVISIBLE (-6025 4725);
FORCEPROP 1 LAST BODY_TYPE PLUMBING
J 0
(-6025 4775);
DISPLAY 0.872340 (-6025 4775);
PAINT GREEN (-6025 4775);
DISPLAY INVISIBLE (-6025 4775);
FORCEPROP 1 LAST HDL_TAP TRUE
J 0
(-5700 4600);
DISPLAY 0.872340 (-5700 4600);
DISPLAY INVISIBLE (-5700 4600);
FORCEPROP 1 LAST PATH I112
J 0
(-6027 4725);
DISPLAY 0.872340 (-6027 4725);
PAINT GREEN (-6027 4725);
DISPLAY INVISIBLE (-6027 4725);
FORCEADD TAP..1
(-6025 4775);
FORCEPROP 3 LASTPIN (-6075 4775) SIG_NAME M_K_CPU0_SA_DQ<19>
J 0
(-6065 4785);
DISPLAY 0.659574 (-6065 4785);
PAINT MONO (-6065 4785);
DISPLAY INVISIBLE (-6065 4785);
FORCEPROP 1 LASTPIN (-6075 4775) BN 19
J 0
(-6087 4783);
DISPLAY 0.489362 (-6087 4783);
PAINT GREEN (-6087 4783);
FORCEPROP 2 LAST CDS_LIB mstr_standard
J 0
(-6025 4775);
DISPLAY 0.723404 (-6025 4775);
PAINT MONO (-6025 4775);
DISPLAY INVISIBLE (-6025 4775);
FORCEPROP 1 LAST BODY_TYPE PLUMBING
J 0
(-6025 4825);
DISPLAY 0.872340 (-6025 4825);
PAINT GREEN (-6025 4825);
DISPLAY INVISIBLE (-6025 4825);
FORCEPROP 1 LAST HDL_TAP TRUE
J 0
(-5700 4650);
DISPLAY 0.872340 (-5700 4650);
DISPLAY INVISIBLE (-5700 4650);
FORCEPROP 1 LAST PATH I113
J 0
(-6027 4775);
DISPLAY 0.872340 (-6027 4775);
PAINT GREEN (-6027 4775);
DISPLAY INVISIBLE (-6027 4775);
FORCEADD TAP..1
(-6025 4825);
FORCEPROP 3 LASTPIN (-6075 4825) SIG_NAME M_K_CPU0_SA_DQ<20>
J 0
(-6065 4835);
DISPLAY 0.659574 (-6065 4835);
PAINT MONO (-6065 4835);
DISPLAY INVISIBLE (-6065 4835);
FORCEPROP 1 LASTPIN (-6075 4825) BN 20
J 0
(-6087 4833);
DISPLAY 0.489362 (-6087 4833);
PAINT GREEN (-6087 4833);
FORCEPROP 2 LAST CDS_LIB mstr_standard
J 0
(-6025 4825);
DISPLAY 0.723404 (-6025 4825);
PAINT MONO (-6025 4825);
DISPLAY INVISIBLE (-6025 4825);
FORCEPROP 1 LAST BODY_TYPE PLUMBING
J 0
(-6025 4875);
DISPLAY 0.872340 (-6025 4875);
PAINT GREEN (-6025 4875);
DISPLAY INVISIBLE (-6025 4875);
FORCEPROP 1 LAST HDL_TAP TRUE
J 0
(-5700 4700);
DISPLAY 0.872340 (-5700 4700);
DISPLAY INVISIBLE (-5700 4700);
FORCEPROP 1 LAST PATH I114
J 0
(-6027 4825);
DISPLAY 0.872340 (-6027 4825);
PAINT GREEN (-6027 4825);
DISPLAY INVISIBLE (-6027 4825);
FORCEADD TAP..1
(-6025 4875);
FORCEPROP 3 LASTPIN (-6075 4875) SIG_NAME M_K_CPU0_SA_DQ<21>
J 0
(-6065 4885);
DISPLAY 0.659574 (-6065 4885);
PAINT MONO (-6065 4885);
DISPLAY INVISIBLE (-6065 4885);
FORCEPROP 1 LASTPIN (-6075 4875) BN 21
J 0
(-6087 4883);
DISPLAY 0.489362 (-6087 4883);
PAINT GREEN (-6087 4883);
FORCEPROP 2 LAST CDS_LIB mstr_standard
J 0
(-6025 4875);
DISPLAY 0.723404 (-6025 4875);
PAINT MONO (-6025 4875);
DISPLAY INVISIBLE (-6025 4875);
FORCEPROP 1 LAST BODY_TYPE PLUMBING
J 0
(-6025 4925);
DISPLAY 0.872340 (-6025 4925);
PAINT GREEN (-6025 4925);
DISPLAY INVISIBLE (-6025 4925);
FORCEPROP 1 LAST HDL_TAP TRUE
J 0
(-5700 4750);
DISPLAY 0.872340 (-5700 4750);
DISPLAY INVISIBLE (-5700 4750);
FORCEPROP 1 LAST PATH I115
J 0
(-6027 4875);
DISPLAY 0.872340 (-6027 4875);
PAINT GREEN (-6027 4875);
DISPLAY INVISIBLE (-6027 4875);
FORCEADD TAP..1
(-6025 4925);
FORCEPROP 3 LASTPIN (-6075 4925) SIG_NAME M_K_CPU0_SA_DQ<22>
J 0
(-6065 4935);
DISPLAY 0.659574 (-6065 4935);
PAINT MONO (-6065 4935);
DISPLAY INVISIBLE (-6065 4935);
FORCEPROP 1 LASTPIN (-6075 4925) BN 22
J 0
(-6087 4933);
DISPLAY 0.489362 (-6087 4933);
PAINT GREEN (-6087 4933);
FORCEPROP 2 LAST CDS_LIB mstr_standard
J 0
(-6025 4925);
DISPLAY 0.723404 (-6025 4925);
PAINT MONO (-6025 4925);
DISPLAY INVISIBLE (-6025 4925);
FORCEPROP 1 LAST BODY_TYPE PLUMBING
J 0
(-6025 4975);
DISPLAY 0.872340 (-6025 4975);
PAINT GREEN (-6025 4975);
DISPLAY INVISIBLE (-6025 4975);
FORCEPROP 1 LAST HDL_TAP TRUE
J 0
(-5700 4800);
DISPLAY 0.872340 (-5700 4800);
DISPLAY INVISIBLE (-5700 4800);
FORCEPROP 1 LAST PATH I116
J 0
(-6027 4925);
DISPLAY 0.872340 (-6027 4925);
PAINT GREEN (-6027 4925);
DISPLAY INVISIBLE (-6027 4925);
FORCEADD TAP..1
(-6025 4975);
FORCEPROP 3 LASTPIN (-6075 4975) SIG_NAME M_K_CPU0_SA_DQ<23>
J 0
(-6065 4985);
DISPLAY 0.659574 (-6065 4985);
PAINT MONO (-6065 4985);
DISPLAY INVISIBLE (-6065 4985);
FORCEPROP 1 LASTPIN (-6075 4975) BN 23
J 0
(-6087 4983);
DISPLAY 0.489362 (-6087 4983);
PAINT GREEN (-6087 4983);
FORCEPROP 2 LAST CDS_LIB mstr_standard
J 0
(-6025 4975);
DISPLAY 0.723404 (-6025 4975);
PAINT MONO (-6025 4975);
DISPLAY INVISIBLE (-6025 4975);
FORCEPROP 1 LAST BODY_TYPE PLUMBING
J 0
(-6025 5025);
DISPLAY 0.872340 (-6025 5025);
PAINT GREEN (-6025 5025);
DISPLAY INVISIBLE (-6025 5025);
FORCEPROP 1 LAST HDL_TAP TRUE
J 0
(-5700 4850);
DISPLAY 0.872340 (-5700 4850);
DISPLAY INVISIBLE (-5700 4850);
FORCEPROP 1 LAST PATH I117
J 0
(-6027 4975);
DISPLAY 0.872340 (-6027 4975);
PAINT GREEN (-6027 4975);
DISPLAY INVISIBLE (-6027 4975);
FORCEADD TAP..1
(-6025 5025);
FORCEPROP 3 LASTPIN (-6075 5025) SIG_NAME M_K_CPU0_SA_DQ<24>
J 0
(-6065 5035);
DISPLAY 0.659574 (-6065 5035);
PAINT MONO (-6065 5035);
DISPLAY INVISIBLE (-6065 5035);
FORCEPROP 1 LASTPIN (-6075 5025) BN 24
J 0
(-6087 5033);
DISPLAY 0.489362 (-6087 5033);
PAINT GREEN (-6087 5033);
FORCEPROP 2 LAST CDS_LIB mstr_standard
J 0
(-6025 5025);
DISPLAY 0.723404 (-6025 5025);
PAINT MONO (-6025 5025);
DISPLAY INVISIBLE (-6025 5025);
FORCEPROP 1 LAST BODY_TYPE PLUMBING
J 0
(-6025 5075);
DISPLAY 0.872340 (-6025 5075);
PAINT GREEN (-6025 5075);
DISPLAY INVISIBLE (-6025 5075);
FORCEPROP 1 LAST HDL_TAP TRUE
J 0
(-5700 4900);
DISPLAY 0.872340 (-5700 4900);
DISPLAY INVISIBLE (-5700 4900);
FORCEPROP 1 LAST PATH I118
J 0
(-6027 5025);
DISPLAY 0.872340 (-6027 5025);
PAINT GREEN (-6027 5025);
DISPLAY INVISIBLE (-6027 5025);
FORCEADD TAP..1
(-6025 5075);
FORCEPROP 3 LASTPIN (-6075 5075) SIG_NAME M_K_CPU0_SA_DQ<25>
J 0
(-6065 5085);
DISPLAY 0.659574 (-6065 5085);
PAINT MONO (-6065 5085);
DISPLAY INVISIBLE (-6065 5085);
FORCEPROP 1 LASTPIN (-6075 5075) BN 25
J 0
(-6087 5083);
DISPLAY 0.489362 (-6087 5083);
PAINT GREEN (-6087 5083);
FORCEPROP 2 LAST CDS_LIB mstr_standard
J 0
(-6025 5075);
DISPLAY 0.723404 (-6025 5075);
PAINT MONO (-6025 5075);
DISPLAY INVISIBLE (-6025 5075);
FORCEPROP 1 LAST BODY_TYPE PLUMBING
J 0
(-6025 5125);
DISPLAY 0.872340 (-6025 5125);
PAINT GREEN (-6025 5125);
DISPLAY INVISIBLE (-6025 5125);
FORCEPROP 1 LAST HDL_TAP TRUE
J 0
(-5700 4950);
DISPLAY 0.872340 (-5700 4950);
DISPLAY INVISIBLE (-5700 4950);
FORCEPROP 1 LAST PATH I119
J 0
(-6027 5075);
DISPLAY 0.872340 (-6027 5075);
PAINT GREEN (-6027 5075);
DISPLAY INVISIBLE (-6027 5075);
FORCEADD OFFPAGE..1
(-8325 4075);
FORCEPROP 2 LAST $XR0 20 
J 0
(-8546 4075);
DISPLAY 0.638298 (-8546 4075);
PAINT MONO (-8546 4075);
FORCEPROP 2 LAST PATH I12
J 0
(-8275 4150);
DISPLAY 1.021277 (-8275 4150);
DISPLAY INVISIBLE (-8275 4150);
FORCEPROP 1 LAST COMMENT_BODY TRUE
J 0
(-8200 3975);
DISPLAY 0.872340 (-8200 3975);
PAINT GREEN (-8200 3975);
DISPLAY INVISIBLE (-8200 3975);
FORCEPROP 1 LAST OFFPAGE TRUE
J 0
(-8000 3950);
DISPLAY 0.872340 (-8000 3950);
PAINT GREEN (-8000 3950);
DISPLAY INVISIBLE (-8000 3950);
FORCEPROP 2 LAST CDS_LIB mstr_standard
J 0
(-8325 4075);
DISPLAY 0.808511 (-8325 4075);
DISPLAY INVISIBLE (-8325 4075);
FORCEADD TAP..1
(-6025 5125);
FORCEPROP 3 LASTPIN (-6075 5125) SIG_NAME M_K_CPU0_SA_DQ<26>
J 0
(-6065 5135);
DISPLAY 0.659574 (-6065 5135);
PAINT MONO (-6065 5135);
DISPLAY INVISIBLE (-6065 5135);
FORCEPROP 1 LASTPIN (-6075 5125) BN 26
J 0
(-6087 5133);
DISPLAY 0.489362 (-6087 5133);
PAINT GREEN (-6087 5133);
FORCEPROP 2 LAST CDS_LIB mstr_standard
J 0
(-6025 5125);
DISPLAY 0.723404 (-6025 5125);
PAINT MONO (-6025 5125);
DISPLAY INVISIBLE (-6025 5125);
FORCEPROP 1 LAST BODY_TYPE PLUMBING
J 0
(-6025 5175);
DISPLAY 0.872340 (-6025 5175);
PAINT GREEN (-6025 5175);
DISPLAY INVISIBLE (-6025 5175);
FORCEPROP 1 LAST HDL_TAP TRUE
J 0
(-5700 5000);
DISPLAY 0.872340 (-5700 5000);
DISPLAY INVISIBLE (-5700 5000);
FORCEPROP 1 LAST PATH I120
J 0
(-6027 5125);
DISPLAY 0.872340 (-6027 5125);
PAINT GREEN (-6027 5125);
DISPLAY INVISIBLE (-6027 5125);
FORCEADD TAP..1
(-6025 5175);
FORCEPROP 3 LASTPIN (-6075 5175) SIG_NAME M_K_CPU0_SA_DQ<27>
J 0
(-6065 5185);
DISPLAY 0.659574 (-6065 5185);
PAINT MONO (-6065 5185);
DISPLAY INVISIBLE (-6065 5185);
FORCEPROP 1 LASTPIN (-6075 5175) BN 27
J 0
(-6087 5183);
DISPLAY 0.489362 (-6087 5183);
PAINT GREEN (-6087 5183);
FORCEPROP 2 LAST CDS_LIB mstr_standard
J 0
(-6025 5175);
DISPLAY 0.723404 (-6025 5175);
PAINT MONO (-6025 5175);
DISPLAY INVISIBLE (-6025 5175);
FORCEPROP 1 LAST BODY_TYPE PLUMBING
J 0
(-6025 5225);
DISPLAY 0.872340 (-6025 5225);
PAINT GREEN (-6025 5225);
DISPLAY INVISIBLE (-6025 5225);
FORCEPROP 1 LAST HDL_TAP TRUE
J 0
(-5700 5050);
DISPLAY 0.872340 (-5700 5050);
DISPLAY INVISIBLE (-5700 5050);
FORCEPROP 1 LAST PATH I121
J 0
(-6027 5175);
DISPLAY 0.872340 (-6027 5175);
PAINT GREEN (-6027 5175);
DISPLAY INVISIBLE (-6027 5175);
FORCEADD TAP..1
(-6025 5225);
FORCEPROP 3 LASTPIN (-6075 5225) SIG_NAME M_K_CPU0_SA_DQ<28>
J 0
(-6065 5235);
DISPLAY 0.659574 (-6065 5235);
PAINT MONO (-6065 5235);
DISPLAY INVISIBLE (-6065 5235);
FORCEPROP 1 LASTPIN (-6075 5225) BN 28
J 0
(-6087 5233);
DISPLAY 0.489362 (-6087 5233);
PAINT GREEN (-6087 5233);
FORCEPROP 2 LAST CDS_LIB mstr_standard
J 0
(-6025 5225);
DISPLAY 0.723404 (-6025 5225);
PAINT MONO (-6025 5225);
DISPLAY INVISIBLE (-6025 5225);
FORCEPROP 1 LAST BODY_TYPE PLUMBING
J 0
(-6025 5275);
DISPLAY 0.872340 (-6025 5275);
PAINT GREEN (-6025 5275);
DISPLAY INVISIBLE (-6025 5275);
FORCEPROP 1 LAST HDL_TAP TRUE
J 0
(-5700 5100);
DISPLAY 0.872340 (-5700 5100);
DISPLAY INVISIBLE (-5700 5100);
FORCEPROP 1 LAST PATH I122
J 0
(-6027 5225);
DISPLAY 0.872340 (-6027 5225);
PAINT GREEN (-6027 5225);
DISPLAY INVISIBLE (-6027 5225);
FORCEADD TAP..1
(-6025 5325);
FORCEPROP 3 LASTPIN (-6075 5325) SIG_NAME M_K_CPU0_SA_DQ<30>
J 0
(-6065 5335);
DISPLAY 0.659574 (-6065 5335);
PAINT MONO (-6065 5335);
DISPLAY INVISIBLE (-6065 5335);
FORCEPROP 1 LASTPIN (-6075 5325) BN 30
J 0
(-6087 5333);
DISPLAY 0.489362 (-6087 5333);
PAINT GREEN (-6087 5333);
FORCEPROP 2 LAST CDS_LIB mstr_standard
J 0
(-6025 5325);
DISPLAY 0.723404 (-6025 5325);
PAINT MONO (-6025 5325);
DISPLAY INVISIBLE (-6025 5325);
FORCEPROP 1 LAST BODY_TYPE PLUMBING
J 0
(-6025 5375);
DISPLAY 0.872340 (-6025 5375);
PAINT GREEN (-6025 5375);
DISPLAY INVISIBLE (-6025 5375);
FORCEPROP 1 LAST HDL_TAP TRUE
J 0
(-5700 5200);
DISPLAY 0.872340 (-5700 5200);
DISPLAY INVISIBLE (-5700 5200);
FORCEPROP 1 LAST PATH I123
J 0
(-6027 5325);
DISPLAY 0.872340 (-6027 5325);
PAINT GREEN (-6027 5325);
DISPLAY INVISIBLE (-6027 5325);
FORCEADD TAP..1
(-6025 5275);
FORCEPROP 3 LASTPIN (-6075 5275) SIG_NAME M_K_CPU0_SA_DQ<29>
J 0
(-6065 5285);
DISPLAY 0.659574 (-6065 5285);
PAINT MONO (-6065 5285);
DISPLAY INVISIBLE (-6065 5285);
FORCEPROP 1 LASTPIN (-6075 5275) BN 29
J 0
(-6087 5283);
DISPLAY 0.489362 (-6087 5283);
PAINT GREEN (-6087 5283);
FORCEPROP 2 LAST CDS_LIB mstr_standard
J 0
(-6025 5275);
DISPLAY 0.723404 (-6025 5275);
PAINT MONO (-6025 5275);
DISPLAY INVISIBLE (-6025 5275);
FORCEPROP 1 LAST BODY_TYPE PLUMBING
J 0
(-6025 5325);
DISPLAY 0.872340 (-6025 5325);
PAINT GREEN (-6025 5325);
DISPLAY INVISIBLE (-6025 5325);
FORCEPROP 1 LAST HDL_TAP TRUE
J 0
(-5700 5150);
DISPLAY 0.872340 (-5700 5150);
DISPLAY INVISIBLE (-5700 5150);
FORCEPROP 1 LAST PATH I124
J 0
(-6027 5275);
DISPLAY 0.872340 (-6027 5275);
PAINT GREEN (-6027 5275);
DISPLAY INVISIBLE (-6027 5275);
FORCEADD TAP..1
(-6025 5375);
FORCEPROP 3 LASTPIN (-6075 5375) SIG_NAME M_K_CPU0_SA_DQ<31>
J 0
(-6065 5385);
DISPLAY 0.659574 (-6065 5385);
PAINT MONO (-6065 5385);
DISPLAY INVISIBLE (-6065 5385);
FORCEPROP 1 LASTPIN (-6075 5375) BN 31
J 0
(-6087 5383);
DISPLAY 0.489362 (-6087 5383);
PAINT GREEN (-6087 5383);
FORCEPROP 2 LAST CDS_LIB mstr_standard
J 0
(-6025 5375);
DISPLAY 0.723404 (-6025 5375);
PAINT MONO (-6025 5375);
DISPLAY INVISIBLE (-6025 5375);
FORCEPROP 1 LAST BODY_TYPE PLUMBING
J 0
(-6025 5425);
DISPLAY 0.872340 (-6025 5425);
PAINT GREEN (-6025 5425);
DISPLAY INVISIBLE (-6025 5425);
FORCEPROP 1 LAST HDL_TAP TRUE
J 0
(-5700 5250);
DISPLAY 0.872340 (-5700 5250);
DISPLAY INVISIBLE (-5700 5250);
FORCEPROP 1 LAST PATH I125
J 0
(-6027 5375);
DISPLAY 0.872340 (-6027 5375);
PAINT GREEN (-6027 5375);
DISPLAY INVISIBLE (-6027 5375);
FORCEADD OFFPAGE..3
(-5350 5425);
FORCEPROP 2 LAST $XR0 20 
J 0
(-5136 5425);
DISPLAY 0.638298 (-5136 5425);
PAINT MONO (-5136 5425);
FORCEPROP 2 LAST PATH I126
J 0
(-5150 5500);
DISPLAY 1.021277 (-5150 5500);
DISPLAY INVISIBLE (-5150 5500);
FORCEPROP 1 LAST COMMENT_BODY TRUE
J 0
(-5400 5325);
DISPLAY 0.872340 (-5400 5325);
PAINT GREEN (-5400 5325);
DISPLAY INVISIBLE (-5400 5325);
FORCEPROP 1 LAST OFFPAGE TRUE
J 0
(-5025 5300);
DISPLAY 0.872340 (-5025 5300);
PAINT GREEN (-5025 5300);
DISPLAY INVISIBLE (-5025 5300);
FORCEPROP 2 LAST CDS_LIB mstr_standard
J 0
(-5350 5425);
DISPLAY 0.723404 (-5350 5425);
PAINT MONO (-5350 5425);
DISPLAY INVISIBLE (-5350 5425);
FORCEADD OFFPAGE..5
(-7200 1450);
FORCEPROP 2 LAST $XR0 95 
J 0
(-7424 1450);
DISPLAY 0.638298 (-7424 1450);
PAINT MONO (-7424 1450);
FORCEPROP 2 LAST PATH I127
J 0
(-7450 1500);
DISPLAY 1.021277 (-7450 1500);
DISPLAY INVISIBLE (-7450 1500);
FORCEPROP 1 LAST COMMENT_BODY TRUE
J 0
(-7100 1375);
DISPLAY 0.872340 (-7100 1375);
PAINT GREEN (-7100 1375);
DISPLAY INVISIBLE (-7100 1375);
FORCEPROP 1 LAST OFFPAGE TRUE
J 0
(-6875 1325);
DISPLAY 0.872340 (-6875 1325);
PAINT GREEN (-6875 1325);
DISPLAY INVISIBLE (-6875 1325);
FORCEPROP 2 LAST BOM_COST MEM
J 0
(-7275 1525);
DISPLAY 0.808511 (-7275 1525);
DISPLAY INVISIBLE (-7275 1525);
FORCEPROP 2 LAST CDS_LIB mstr_standard
J 0
(-7200 1450);
DISPLAY 0.808511 (-7200 1450);
DISPLAY INVISIBLE (-7200 1450);
FORCEADD GND..1
(-6425 1050);
FORCEPROP 3 LASTPIN (-6425 1100) SIG_NAME GND\g
J 0
(-6415 1110);
DISPLAY 0.659574 (-6415 1110);
PAINT MONO (-6415 1110);
DISPLAY INVISIBLE (-6415 1110);
FORCEPROP 2 LAST CDS_LIB mstr_symbols
J 0
(-6425 1050);
DISPLAY 0.808511 (-6425 1050);
DISPLAY INVISIBLE (-6425 1050);
FORCEPROP 2 LAST BOM_COST MEM
J 0
(-6525 1125);
DISPLAY 0.808511 (-6525 1125);
DISPLAY INVISIBLE (-6525 1125);
FORCEPROP 1 LAST SIZE 1B
J 0
(-6350 1000);
DISPLAY 0.851064 (-6350 1000);
PAINT GREEN (-6350 1000);
DISPLAY INVISIBLE (-6350 1000);
FORCEPROP 1 LAST BODY_TYPE PLUMBING
J 0
(-6470 1007);
DISPLAY 0.340426 (-6470 1007);
PAINT GREEN (-6470 1007);
DISPLAY INVISIBLE (-6470 1007);
FORCEPROP 1 LAST PATH I128
J 0
(-6350 1050);
DISPLAY 0.872340 (-6350 1050);
PAINT AQUA (-6350 1050);
DISPLAY INVISIBLE (-6350 1050);
FORCEPROP 1 LAST VOLTAGE 0.0
J 0
(-6470 1007);
DISPLAY 0.723404 (-6470 1007);
PAINT SKYBLUE (-6470 1007);
DISPLAY INVISIBLE (-6470 1007);
FORCEPROP 1 LAST HDL_POWER GND
J 0
(-6425 1200);
DISPLAY 0.851064 (-6425 1200);
PAINT GREEN (-6425 1200);
DISPLAY INVISIBLE (-6425 1200);
FORCEADD Q_RES..2
(-6425 1275);
FORCEPROP 1 LAST LOCATION R768
J 0
(-6380 1400);
DISPLAY 0.489362 (-6380 1400);
PAINT SKYBLUE (-6380 1400);
FORCEPROP 0 LAST $SEC 1
J 0
(-6375 1450);
DISPLAY 0.680851 (-6375 1450);
PAINT MONO (-6375 1450);
DISPLAY INVISIBLE (-6375 1450);
FORCEPROP 0 LAST CDS_SEC 1
J 0
(-6375 1450);
DISPLAY 1.021277 (-6375 1450);
DISPLAY INVISIBLE (-6375 1450);
FORCEPROP 1 LASTPIN (-6425 1375) $PN 1
J 0
(-6420 1337);
DISPLAY 0.489362 (-6420 1337);
PAINT MONO (-6420 1337);
FORCEPROP 1 LASTPIN (-6425 1175) $PN 2
J 0
(-6420 1185);
DISPLAY 0.489362 (-6420 1185);
PAINT MONO (-6420 1185);
FORCEPROP 1 LAST WATTAGE 1/16W
J 0
(-6385 1250);
DISPLAY 0.489362 (-6385 1250);
PAINT SKYBLUE (-6385 1250);
FORCEPROP 1 LAST MATERIAL CHIP
J 0
(-6385 1200);
DISPLAY 0.489362 (-6385 1200);
PAINT SKYBLUE (-6385 1200);
FORCEPROP 1 LAST TOLERANCE 1%
J 0
(-6380 1300);
DISPLAY 0.489362 (-6380 1300);
PAINT SKYBLUE (-6380 1300);
FORCEPROP 1 LAST VALUE 54.9K
J 0
(-6380 1350);
DISPLAY 0.489362 (-6380 1350);
PAINT SKYBLUE (-6380 1350);
FORCEPROP 1 LAST PART_NUMBER TMP_QCS35492FB14
J 0
(-6385 1150);
DISPLAY 0.489362 (-6385 1150);
PAINT SKYBLUE (-6385 1150);
FORCEPROP 1 LAST PACK_TYPE 0402LF
J 0
(-6385 1100);
DISPLAY 0.489362 (-6385 1100);
PAINT SKYBLUE (-6385 1100);
FORCEPROP 2 LAST CDS_LIB pure_quanta
J 0
(-6425 1275);
DISPLAY INVISIBLE (-6425 1275);
FORCEPROP 1 LAST PATH I129
J 0
(-6375 1450);
DISPLAY 0.978723 (-6375 1450);
PAINT WHITE (-6375 1450);
DISPLAY INVISIBLE (-6375 1450);
FORCEADD OFFPAGE..6
(-8325 4025);
FORCEPROP 2 LAST $XR0 20 
J 0
(-8574 4025);
DISPLAY 0.638298 (-8574 4025);
PAINT MONO (-8574 4025);
FORCEPROP 2 LAST PATH I13
J 0
(-8275 4100);
DISPLAY 1.021277 (-8275 4100);
DISPLAY INVISIBLE (-8275 4100);
FORCEPROP 1 LAST COMMENT_BODY TRUE
J 0
(-8225 3950);
DISPLAY 0.872340 (-8225 3950);
PAINT GREEN (-8225 3950);
DISPLAY INVISIBLE (-8225 3950);
FORCEPROP 1 LAST OFFPAGE TRUE
J 0
(-8000 3900);
DISPLAY 0.872340 (-8000 3900);
PAINT GREEN (-8000 3900);
DISPLAY INVISIBLE (-8000 3900);
FORCEPROP 2 LAST CDS_LIB mstr_standard
J 0
(-8325 4025);
DISPLAY 0.723404 (-8325 4025);
PAINT MONO (-8325 4025);
DISPLAY INVISIBLE (-8325 4025);
FORCEADD GND..1
(-2125 1900);
FORCEPROP 3 LASTPIN (-2125 1950) SIG_NAME GND\g
J 0
(-2115 1960);
DISPLAY 0.659574 (-2115 1960);
PAINT MONO (-2115 1960);
DISPLAY INVISIBLE (-2115 1960);
FORCEPROP 1 LAST SIZE 1B
J 0
(-2050 1850);
DISPLAY 0.851064 (-2050 1850);
PAINT GREEN (-2050 1850);
DISPLAY INVISIBLE (-2050 1850);
FORCEPROP 2 LAST CDS_LIB mstr_symbols
J 0
(-2125 1900);
DISPLAY 0.723404 (-2125 1900);
DISPLAY INVISIBLE (-2125 1900);
FORCEPROP 1 LAST BODY_TYPE PLUMBING
J 0
(-2170 1857);
DISPLAY 0.340426 (-2170 1857);
PAINT GREEN (-2170 1857);
DISPLAY INVISIBLE (-2170 1857);
FORCEPROP 1 LAST PATH I130
J 0
(-2050 1900);
DISPLAY 0.872340 (-2050 1900);
PAINT AQUA (-2050 1900);
DISPLAY INVISIBLE (-2050 1900);
FORCEPROP 1 LAST VOLTAGE 0.0
J 0
(-2170 1857);
DISPLAY 0.723404 (-2170 1857);
PAINT SKYBLUE (-2170 1857);
DISPLAY INVISIBLE (-2170 1857);
FORCEPROP 1 LAST HDL_POWER GND
J 0
(-2125 2050);
DISPLAY 0.851064 (-2125 2050);
PAINT GREEN (-2125 2050);
DISPLAY INVISIBLE (-2125 2050);
FORCEADD OFFPAGE..1
(-8325 4375);
FORCEPROP 2 LAST $XR0 20 
J 0
(-8546 4375);
DISPLAY 0.638298 (-8546 4375);
PAINT MONO (-8546 4375);
FORCEPROP 2 LAST PATH I14
J 0
(-8275 4450);
DISPLAY 1.021277 (-8275 4450);
DISPLAY INVISIBLE (-8275 4450);
FORCEPROP 1 LAST COMMENT_BODY TRUE
J 0
(-8200 4275);
DISPLAY 0.872340 (-8200 4275);
PAINT GREEN (-8200 4275);
DISPLAY INVISIBLE (-8200 4275);
FORCEPROP 1 LAST OFFPAGE TRUE
J 0
(-8000 4250);
DISPLAY 0.872340 (-8000 4250);
PAINT GREEN (-8000 4250);
DISPLAY INVISIBLE (-8000 4250);
FORCEPROP 2 LAST CDS_LIB mstr_standard
J 0
(-8325 4375);
DISPLAY 0.808511 (-8325 4375);
DISPLAY INVISIBLE (-8325 4375);
FORCEADD GND..1
(-325 1675);
FORCEPROP 3 LASTPIN (-325 1725) SIG_NAME GND\g
J 0
(-315 1735);
DISPLAY 0.659574 (-315 1735);
PAINT MONO (-315 1735);
DISPLAY INVISIBLE (-315 1735);
FORCEPROP 1 LAST SIZE 1B
J 0
(-250 1625);
DISPLAY 0.851064 (-250 1625);
PAINT GREEN (-250 1625);
DISPLAY INVISIBLE (-250 1625);
FORCEPROP 2 LAST CDS_LIB mstr_symbols
J 0
(-325 1675);
DISPLAY 0.723404 (-325 1675);
DISPLAY INVISIBLE (-325 1675);
FORCEPROP 1 LAST BODY_TYPE PLUMBING
J 0
(-370 1632);
DISPLAY 0.340426 (-370 1632);
PAINT GREEN (-370 1632);
DISPLAY INVISIBLE (-370 1632);
FORCEPROP 1 LAST PATH I144
J 0
(-250 1675);
DISPLAY 0.872340 (-250 1675);
PAINT AQUA (-250 1675);
DISPLAY INVISIBLE (-250 1675);
FORCEPROP 1 LAST VOLTAGE 0.0
J 0
(-370 1632);
DISPLAY 0.723404 (-370 1632);
PAINT SKYBLUE (-370 1632);
DISPLAY INVISIBLE (-370 1632);
FORCEPROP 1 LAST HDL_POWER GND
J 0
(-325 1825);
DISPLAY 0.851064 (-325 1825);
PAINT GREEN (-325 1825);
DISPLAY INVISIBLE (-325 1825);
FORCEADD OFFPAGE..1
(-8325 4225);
FORCEPROP 2 LAST $XR0 20 
J 0
(-8546 4225);
DISPLAY 0.638298 (-8546 4225);
PAINT MONO (-8546 4225);
FORCEPROP 2 LAST PATH I15
J 0
(-8275 4300);
DISPLAY 1.021277 (-8275 4300);
DISPLAY INVISIBLE (-8275 4300);
FORCEPROP 1 LAST COMMENT_BODY TRUE
J 0
(-8200 4125);
DISPLAY 0.872340 (-8200 4125);
PAINT GREEN (-8200 4125);
DISPLAY INVISIBLE (-8200 4125);
FORCEPROP 1 LAST OFFPAGE TRUE
J 0
(-8000 4100);
DISPLAY 0.872340 (-8000 4100);
PAINT GREEN (-8000 4100);
DISPLAY INVISIBLE (-8000 4100);
FORCEPROP 2 LAST CDS_LIB mstr_standard
J 0
(-8325 4225);
DISPLAY 0.808511 (-8325 4225);
DISPLAY INVISIBLE (-8325 4225);
FORCEADD OFFPAGE..1
(-8325 4275);
FORCEPROP 2 LAST $XR0 20 
J 0
(-8546 4275);
DISPLAY 0.638298 (-8546 4275);
PAINT MONO (-8546 4275);
FORCEPROP 2 LAST PATH I16
J 0
(-8275 4350);
DISPLAY 1.021277 (-8275 4350);
DISPLAY INVISIBLE (-8275 4350);
FORCEPROP 1 LAST COMMENT_BODY TRUE
J 0
(-8200 4175);
DISPLAY 0.872340 (-8200 4175);
PAINT GREEN (-8200 4175);
DISPLAY INVISIBLE (-8200 4175);
FORCEPROP 1 LAST OFFPAGE TRUE
J 0
(-8000 4150);
DISPLAY 0.872340 (-8000 4150);
PAINT GREEN (-8000 4150);
DISPLAY INVISIBLE (-8000 4150);
FORCEPROP 2 LAST CDS_LIB mstr_standard
J 0
(-8325 4275);
DISPLAY 0.723404 (-8325 4275);
PAINT MONO (-8325 4275);
DISPLAY INVISIBLE (-8325 4275);
FORCEADD OFFPAGE..1
(-8325 4425);
FORCEPROP 2 LAST $XR0 20 
J 0
(-8546 4425);
DISPLAY 0.638298 (-8546 4425);
PAINT MONO (-8546 4425);
FORCEPROP 2 LAST PATH I17
J 0
(-8275 4500);
DISPLAY 1.021277 (-8275 4500);
DISPLAY INVISIBLE (-8275 4500);
FORCEPROP 1 LAST COMMENT_BODY TRUE
J 0
(-8200 4325);
DISPLAY 0.872340 (-8200 4325);
PAINT GREEN (-8200 4325);
DISPLAY INVISIBLE (-8200 4325);
FORCEPROP 1 LAST OFFPAGE TRUE
J 0
(-8000 4300);
DISPLAY 0.872340 (-8000 4300);
PAINT GREEN (-8000 4300);
DISPLAY INVISIBLE (-8000 4300);
FORCEPROP 2 LAST CDS_LIB mstr_standard
J 0
(-8325 4425);
DISPLAY 0.723404 (-8325 4425);
PAINT MONO (-8325 4425);
DISPLAY INVISIBLE (-8325 4425);
FORCEADD SCONN288_DDR506112002KQ..3
(-1225 3675);
FORCEPROP 1 LAST LOCATION J20
J 0
(-1675 5650);
DISPLAY 0.468085 (-1675 5650);
PAINT SKYBLUE (-1675 5650);
FORCEPROP 0 LAST $SEC 3
J 0
(-1675 5800);
DISPLAY 0.680851 (-1675 5800);
PAINT MONO (-1675 5800);
DISPLAY INVISIBLE (-1675 5800);
FORCEPROP 2 LAST CDS_SEC 3
J 0
(-1675 5800);
DISPLAY 1.021277 (-1675 5800);
DISPLAY INVISIBLE (-1675 5800);
FORCEPROP 0 LASTPIN (-625 2075) $PN G1
J 0
(-615 2085);
DISPLAY 0.680851 (-615 2085);
PAINT MONO (-615 2085);
FORCEPROP 0 LASTPIN (-625 2025) $PN G2
J 0
(-615 2035);
DISPLAY 0.680851 (-615 2035);
PAINT MONO (-615 2035);
FORCEPROP 0 LASTPIN (-625 1975) $PN G3
J 0
(-615 1985);
DISPLAY 0.680851 (-615 1985);
PAINT MONO (-615 1985);
FORCEPROP 0 LASTPIN (-1825 5225) $PN 1
J 2
(-1835 5235);
DISPLAY 0.680851 (-1835 5235);
PAINT MONO (-1835 5235);
FORCEPROP 0 LASTPIN (-1825 5275) $PN 145
J 2
(-1835 5285);
DISPLAY 0.680851 (-1835 5285);
PAINT MONO (-1835 5285);
FORCEPROP 0 LASTPIN (-1825 5325) $PN 146
J 2
(-1835 5335);
DISPLAY 0.680851 (-1835 5335);
PAINT MONO (-1835 5335);
FORCEPROP 0 LASTPIN (-625 2175) $PN 6
J 0
(-615 2185);
DISPLAY 0.680851 (-615 2185);
PAINT MONO (-615 2185);
FORCEPROP 0 LASTPIN (-625 2225) $PN 8
J 0
(-615 2235);
DISPLAY 0.680851 (-615 2235);
PAINT MONO (-615 2235);
FORCEPROP 0 LASTPIN (-625 2275) $PN 10
J 0
(-615 2285);
DISPLAY 0.680851 (-615 2285);
PAINT MONO (-615 2285);
FORCEPROP 0 LASTPIN (-625 2325) $PN 13
J 0
(-615 2335);
DISPLAY 0.680851 (-615 2335);
PAINT MONO (-615 2335);
FORCEPROP 0 LASTPIN (-625 2375) $PN 15
J 0
(-615 2385);
DISPLAY 0.680851 (-615 2385);
PAINT MONO (-615 2385);
FORCEPROP 0 LASTPIN (-625 2425) $PN 17
J 0
(-615 2435);
DISPLAY 0.680851 (-615 2435);
PAINT MONO (-615 2435);
FORCEPROP 0 LASTPIN (-625 2475) $PN 19
J 0
(-615 2485);
DISPLAY 0.680851 (-615 2485);
PAINT MONO (-615 2485);
FORCEPROP 0 LASTPIN (-625 2525) $PN 21
J 0
(-615 2535);
DISPLAY 0.680851 (-615 2535);
PAINT MONO (-615 2535);
FORCEPROP 0 LASTPIN (-625 2575) $PN 24
J 0
(-615 2585);
DISPLAY 0.680851 (-615 2585);
PAINT MONO (-615 2585);
FORCEPROP 0 LASTPIN (-625 2625) $PN 26
J 0
(-615 2635);
DISPLAY 0.680851 (-615 2635);
PAINT MONO (-615 2635);
FORCEPROP 0 LASTPIN (-625 2675) $PN 28
J 0
(-615 2685);
DISPLAY 0.680851 (-615 2685);
PAINT MONO (-615 2685);
FORCEPROP 0 LASTPIN (-625 2725) $PN 30
J 0
(-615 2735);
DISPLAY 0.680851 (-615 2735);
PAINT MONO (-615 2735);
FORCEPROP 0 LASTPIN (-625 2775) $PN 32
J 0
(-615 2785);
DISPLAY 0.680851 (-615 2785);
PAINT MONO (-615 2785);
FORCEPROP 0 LASTPIN (-625 2825) $PN 35
J 0
(-615 2835);
DISPLAY 0.680851 (-615 2835);
PAINT MONO (-615 2835);
FORCEPROP 0 LASTPIN (-625 2875) $PN 37
J 0
(-615 2885);
DISPLAY 0.680851 (-615 2885);
PAINT MONO (-615 2885);
FORCEPROP 0 LASTPIN (-625 2925) $PN 39
J 0
(-615 2935);
DISPLAY 0.680851 (-615 2935);
PAINT MONO (-615 2935);
FORCEPROP 0 LASTPIN (-625 2975) $PN 41
J 0
(-615 2985);
DISPLAY 0.680851 (-615 2985);
PAINT MONO (-615 2985);
FORCEPROP 0 LASTPIN (-625 3025) $PN 43
J 0
(-615 3035);
DISPLAY 0.680851 (-615 3035);
PAINT MONO (-615 3035);
FORCEPROP 0 LASTPIN (-625 3075) $PN 46
J 0
(-615 3085);
DISPLAY 0.680851 (-615 3085);
PAINT MONO (-615 3085);
FORCEPROP 0 LASTPIN (-625 3125) $PN 48
J 0
(-615 3135);
DISPLAY 0.680851 (-615 3135);
PAINT MONO (-615 3135);
FORCEPROP 0 LASTPIN (-625 3175) $PN 50
J 0
(-615 3185);
DISPLAY 0.680851 (-615 3185);
PAINT MONO (-615 3185);
FORCEPROP 0 LASTPIN (-625 3225) $PN 52
J 0
(-615 3235);
DISPLAY 0.680851 (-615 3235);
PAINT MONO (-615 3235);
FORCEPROP 0 LASTPIN (-625 3275) $PN 54
J 0
(-615 3285);
DISPLAY 0.680851 (-615 3285);
PAINT MONO (-615 3285);
FORCEPROP 0 LASTPIN (-625 3325) $PN 57
J 0
(-615 3335);
DISPLAY 0.680851 (-615 3335);
PAINT MONO (-615 3335);
FORCEPROP 0 LASTPIN (-625 3375) $PN 59
J 0
(-615 3385);
DISPLAY 0.680851 (-615 3385);
PAINT MONO (-615 3385);
FORCEPROP 0 LASTPIN (-625 3425) $PN 61
J 0
(-615 3435);
DISPLAY 0.680851 (-615 3435);
PAINT MONO (-615 3435);
FORCEPROP 0 LASTPIN (-625 3475) $PN 63
J 0
(-615 3485);
DISPLAY 0.680851 (-615 3485);
PAINT MONO (-615 3485);
FORCEPROP 0 LASTPIN (-625 3525) $PN 65
J 0
(-615 3535);
DISPLAY 0.680851 (-615 3535);
PAINT MONO (-615 3535);
FORCEPROP 0 LASTPIN (-625 3575) $PN 67
J 0
(-615 3585);
DISPLAY 0.680851 (-615 3585);
PAINT MONO (-615 3585);
FORCEPROP 0 LASTPIN (-625 3625) $PN 69
J 0
(-615 3635);
DISPLAY 0.680851 (-615 3635);
PAINT MONO (-615 3635);
FORCEPROP 0 LASTPIN (-625 3675) $PN 71
J 0
(-615 3685);
DISPLAY 0.680851 (-615 3685);
PAINT MONO (-615 3685);
FORCEPROP 0 LASTPIN (-625 3725) $PN 73
J 0
(-615 3735);
DISPLAY 0.680851 (-615 3735);
PAINT MONO (-615 3735);
FORCEPROP 0 LASTPIN (-625 3775) $PN 75
J 0
(-615 3785);
DISPLAY 0.680851 (-615 3785);
PAINT MONO (-615 3785);
FORCEPROP 0 LASTPIN (-625 3825) $PN 77
J 0
(-615 3835);
DISPLAY 0.680851 (-615 3835);
PAINT MONO (-615 3835);
FORCEPROP 0 LASTPIN (-625 3875) $PN 79
J 0
(-615 3885);
DISPLAY 0.680851 (-615 3885);
PAINT MONO (-615 3885);
FORCEPROP 0 LASTPIN (-625 3925) $PN 81
J 0
(-615 3935);
DISPLAY 0.680851 (-615 3935);
PAINT MONO (-615 3935);
FORCEPROP 0 LASTPIN (-625 3975) $PN 83
J 0
(-615 3985);
DISPLAY 0.680851 (-615 3985);
PAINT MONO (-615 3985);
FORCEPROP 0 LASTPIN (-625 4025) $PN 85
J 0
(-615 4035);
DISPLAY 0.680851 (-615 4035);
PAINT MONO (-615 4035);
FORCEPROP 0 LASTPIN (-625 4075) $PN 88
J 0
(-615 4085);
DISPLAY 0.680851 (-615 4085);
PAINT MONO (-615 4085);
FORCEPROP 0 LASTPIN (-625 4125) $PN 90
J 0
(-615 4135);
DISPLAY 0.680851 (-615 4135);
PAINT MONO (-615 4135);
FORCEPROP 0 LASTPIN (-625 4175) $PN 92
J 0
(-615 4185);
DISPLAY 0.680851 (-615 4185);
PAINT MONO (-615 4185);
FORCEPROP 0 LASTPIN (-625 4225) $PN 95
J 0
(-615 4235);
DISPLAY 0.680851 (-615 4235);
PAINT MONO (-615 4235);
FORCEPROP 0 LASTPIN (-625 4275) $PN 97
J 0
(-615 4285);
DISPLAY 0.680851 (-615 4285);
PAINT MONO (-615 4285);
FORCEPROP 0 LASTPIN (-625 4325) $PN 99
J 0
(-615 4335);
DISPLAY 0.680851 (-615 4335);
PAINT MONO (-615 4335);
FORCEPROP 0 LASTPIN (-625 4375) $PN 101
J 0
(-615 4385);
DISPLAY 0.680851 (-615 4385);
PAINT MONO (-615 4385);
FORCEPROP 0 LASTPIN (-625 4425) $PN 103
J 0
(-615 4435);
DISPLAY 0.680851 (-615 4435);
PAINT MONO (-615 4435);
FORCEPROP 0 LASTPIN (-625 4475) $PN 106
J 0
(-615 4485);
DISPLAY 0.680851 (-615 4485);
PAINT MONO (-615 4485);
FORCEPROP 0 LASTPIN (-625 4525) $PN 108
J 0
(-615 4535);
DISPLAY 0.680851 (-615 4535);
PAINT MONO (-615 4535);
FORCEPROP 0 LASTPIN (-625 4575) $PN 110
J 0
(-615 4585);
DISPLAY 0.680851 (-615 4585);
PAINT MONO (-615 4585);
FORCEPROP 0 LASTPIN (-625 4625) $PN 112
J 0
(-615 4635);
DISPLAY 0.680851 (-615 4635);
PAINT MONO (-615 4635);
FORCEPROP 0 LASTPIN (-625 4675) $PN 114
J 0
(-615 4685);
DISPLAY 0.680851 (-615 4685);
PAINT MONO (-615 4685);
FORCEPROP 0 LASTPIN (-625 4725) $PN 117
J 0
(-615 4735);
DISPLAY 0.680851 (-615 4735);
PAINT MONO (-615 4735);
FORCEPROP 0 LASTPIN (-625 4775) $PN 119
J 0
(-615 4785);
DISPLAY 0.680851 (-615 4785);
PAINT MONO (-615 4785);
FORCEPROP 0 LASTPIN (-625 4825) $PN 121
J 0
(-615 4835);
DISPLAY 0.680851 (-615 4835);
PAINT MONO (-615 4835);
FORCEPROP 0 LASTPIN (-625 4875) $PN 123
J 0
(-615 4885);
DISPLAY 0.680851 (-615 4885);
PAINT MONO (-615 4885);
FORCEPROP 0 LASTPIN (-625 4925) $PN 125
J 0
(-615 4935);
DISPLAY 0.680851 (-615 4935);
PAINT MONO (-615 4935);
FORCEPROP 0 LASTPIN (-625 4975) $PN 128
J 0
(-615 4985);
DISPLAY 0.680851 (-615 4985);
PAINT MONO (-615 4985);
FORCEPROP 0 LASTPIN (-625 5025) $PN 130
J 0
(-615 5035);
DISPLAY 0.680851 (-615 5035);
PAINT MONO (-615 5035);
FORCEPROP 0 LASTPIN (-625 5075) $PN 132
J 0
(-615 5085);
DISPLAY 0.680851 (-615 5085);
PAINT MONO (-615 5085);
FORCEPROP 0 LASTPIN (-625 5125) $PN 134
J 0
(-615 5135);
DISPLAY 0.680851 (-615 5135);
PAINT MONO (-615 5135);
FORCEPROP 0 LASTPIN (-625 5175) $PN 136
J 0
(-615 5185);
DISPLAY 0.680851 (-615 5185);
PAINT MONO (-615 5185);
FORCEPROP 0 LASTPIN (-625 5225) $PN 139
J 0
(-615 5235);
DISPLAY 0.680851 (-615 5235);
PAINT MONO (-615 5235);
FORCEPROP 0 LASTPIN (-625 5275) $PN 141
J 0
(-615 5285);
DISPLAY 0.680851 (-615 5285);
PAINT MONO (-615 5285);
FORCEPROP 0 LASTPIN (-625 5325) $PN 143
J 0
(-615 5335);
DISPLAY 0.680851 (-615 5335);
PAINT MONO (-615 5335);
FORCEPROP 0 LASTPIN (-1825 2075) $PN 151
J 2
(-1835 2085);
DISPLAY 0.680851 (-1835 2085);
PAINT MONO (-1835 2085);
FORCEPROP 0 LASTPIN (-1825 2125) $PN 153
J 2
(-1835 2135);
DISPLAY 0.680851 (-1835 2135);
PAINT MONO (-1835 2135);
FORCEPROP 0 LASTPIN (-1825 2175) $PN 155
J 2
(-1835 2185);
DISPLAY 0.680851 (-1835 2185);
PAINT MONO (-1835 2185);
FORCEPROP 0 LASTPIN (-1825 2225) $PN 158
J 2
(-1835 2235);
DISPLAY 0.680851 (-1835 2235);
PAINT MONO (-1835 2235);
FORCEPROP 0 LASTPIN (-1825 2275) $PN 160
J 2
(-1835 2285);
DISPLAY 0.680851 (-1835 2285);
PAINT MONO (-1835 2285);
FORCEPROP 0 LASTPIN (-1825 2325) $PN 162
J 2
(-1835 2335);
DISPLAY 0.680851 (-1835 2335);
PAINT MONO (-1835 2335);
FORCEPROP 0 LASTPIN (-1825 2375) $PN 164
J 2
(-1835 2385);
DISPLAY 0.680851 (-1835 2385);
PAINT MONO (-1835 2385);
FORCEPROP 0 LASTPIN (-1825 2425) $PN 166
J 2
(-1835 2435);
DISPLAY 0.680851 (-1835 2435);
PAINT MONO (-1835 2435);
FORCEPROP 0 LASTPIN (-1825 2475) $PN 169
J 2
(-1835 2485);
DISPLAY 0.680851 (-1835 2485);
PAINT MONO (-1835 2485);
FORCEPROP 0 LASTPIN (-1825 2525) $PN 171
J 2
(-1835 2535);
DISPLAY 0.680851 (-1835 2535);
PAINT MONO (-1835 2535);
FORCEPROP 0 LASTPIN (-1825 2575) $PN 173
J 2
(-1835 2585);
DISPLAY 0.680851 (-1835 2585);
PAINT MONO (-1835 2585);
FORCEPROP 0 LASTPIN (-1825 2625) $PN 175
J 2
(-1835 2635);
DISPLAY 0.680851 (-1835 2635);
PAINT MONO (-1835 2635);
FORCEPROP 0 LASTPIN (-1825 2675) $PN 177
J 2
(-1835 2685);
DISPLAY 0.680851 (-1835 2685);
PAINT MONO (-1835 2685);
FORCEPROP 0 LASTPIN (-1825 2725) $PN 180
J 2
(-1835 2735);
DISPLAY 0.680851 (-1835 2735);
PAINT MONO (-1835 2735);
FORCEPROP 0 LASTPIN (-1825 2775) $PN 182
J 2
(-1835 2785);
DISPLAY 0.680851 (-1835 2785);
PAINT MONO (-1835 2785);
FORCEPROP 0 LASTPIN (-1825 2825) $PN 184
J 2
(-1835 2835);
DISPLAY 0.680851 (-1835 2835);
PAINT MONO (-1835 2835);
FORCEPROP 0 LASTPIN (-1825 2875) $PN 186
J 2
(-1835 2885);
DISPLAY 0.680851 (-1835 2885);
PAINT MONO (-1835 2885);
FORCEPROP 0 LASTPIN (-1825 2925) $PN 188
J 2
(-1835 2935);
DISPLAY 0.680851 (-1835 2935);
PAINT MONO (-1835 2935);
FORCEPROP 0 LASTPIN (-1825 2975) $PN 191
J 2
(-1835 2985);
DISPLAY 0.680851 (-1835 2985);
PAINT MONO (-1835 2985);
FORCEPROP 0 LASTPIN (-1825 3025) $PN 193
J 2
(-1835 3035);
DISPLAY 0.680851 (-1835 3035);
PAINT MONO (-1835 3035);
FORCEPROP 0 LASTPIN (-1825 3075) $PN 195
J 2
(-1835 3085);
DISPLAY 0.680851 (-1835 3085);
PAINT MONO (-1835 3085);
FORCEPROP 0 LASTPIN (-1825 3125) $PN 197
J 2
(-1835 3135);
DISPLAY 0.680851 (-1835 3135);
PAINT MONO (-1835 3135);
FORCEPROP 0 LASTPIN (-1825 3175) $PN 199
J 2
(-1835 3185);
DISPLAY 0.680851 (-1835 3185);
PAINT MONO (-1835 3185);
FORCEPROP 0 LASTPIN (-1825 3225) $PN 202
J 2
(-1835 3235);
DISPLAY 0.680851 (-1835 3235);
PAINT MONO (-1835 3235);
FORCEPROP 0 LASTPIN (-1825 3275) $PN 204
J 2
(-1835 3285);
DISPLAY 0.680851 (-1835 3285);
PAINT MONO (-1835 3285);
FORCEPROP 0 LASTPIN (-1825 3325) $PN 206
J 2
(-1835 3335);
DISPLAY 0.680851 (-1835 3335);
PAINT MONO (-1835 3335);
FORCEPROP 0 LASTPIN (-1825 3375) $PN 208
J 2
(-1835 3385);
DISPLAY 0.680851 (-1835 3385);
PAINT MONO (-1835 3385);
FORCEPROP 0 LASTPIN (-1825 3425) $PN 210
J 2
(-1835 3435);
DISPLAY 0.680851 (-1835 3435);
PAINT MONO (-1835 3435);
FORCEPROP 0 LASTPIN (-1825 3475) $PN 212
J 2
(-1835 3485);
DISPLAY 0.680851 (-1835 3485);
PAINT MONO (-1835 3485);
FORCEPROP 0 LASTPIN (-1825 3525) $PN 214
J 2
(-1835 3535);
DISPLAY 0.680851 (-1835 3535);
PAINT MONO (-1835 3535);
FORCEPROP 0 LASTPIN (-1825 3575) $PN 216
J 2
(-1835 3585);
DISPLAY 0.680851 (-1835 3585);
PAINT MONO (-1835 3585);
FORCEPROP 0 LASTPIN (-1825 3625) $PN 219
J 2
(-1835 3635);
DISPLAY 0.680851 (-1835 3635);
PAINT MONO (-1835 3635);
FORCEPROP 0 LASTPIN (-1825 3675) $PN 222
J 2
(-1835 3685);
DISPLAY 0.680851 (-1835 3685);
PAINT MONO (-1835 3685);
FORCEPROP 0 LASTPIN (-1825 3725) $PN 224
J 2
(-1835 3735);
DISPLAY 0.680851 (-1835 3735);
PAINT MONO (-1835 3735);
FORCEPROP 0 LASTPIN (-1825 3775) $PN 226
J 2
(-1835 3785);
DISPLAY 0.680851 (-1835 3785);
PAINT MONO (-1835 3785);
FORCEPROP 0 LASTPIN (-1825 3825) $PN 228
J 2
(-1835 3835);
DISPLAY 0.680851 (-1835 3835);
PAINT MONO (-1835 3835);
FORCEPROP 0 LASTPIN (-1825 3875) $PN 230
J 2
(-1835 3885);
DISPLAY 0.680851 (-1835 3885);
PAINT MONO (-1835 3885);
FORCEPROP 0 LASTPIN (-1825 3925) $PN 233
J 2
(-1835 3935);
DISPLAY 0.680851 (-1835 3935);
PAINT MONO (-1835 3935);
FORCEPROP 0 LASTPIN (-1825 3975) $PN 235
J 2
(-1835 3985);
DISPLAY 0.680851 (-1835 3985);
PAINT MONO (-1835 3985);
FORCEPROP 0 LASTPIN (-1825 4025) $PN 237
J 2
(-1835 4035);
DISPLAY 0.680851 (-1835 4035);
PAINT MONO (-1835 4035);
FORCEPROP 0 LASTPIN (-1825 4075) $PN 240
J 2
(-1835 4085);
DISPLAY 0.680851 (-1835 4085);
PAINT MONO (-1835 4085);
FORCEPROP 0 LASTPIN (-1825 4125) $PN 242
J 2
(-1835 4135);
DISPLAY 0.680851 (-1835 4135);
PAINT MONO (-1835 4135);
FORCEPROP 0 LASTPIN (-1825 4175) $PN 244
J 2
(-1835 4185);
DISPLAY 0.680851 (-1835 4185);
PAINT MONO (-1835 4185);
FORCEPROP 0 LASTPIN (-1825 4225) $PN 246
J 2
(-1835 4235);
DISPLAY 0.680851 (-1835 4235);
PAINT MONO (-1835 4235);
FORCEPROP 0 LASTPIN (-1825 4275) $PN 248
J 2
(-1835 4285);
DISPLAY 0.680851 (-1835 4285);
PAINT MONO (-1835 4285);
FORCEPROP 0 LASTPIN (-1825 4325) $PN 251
J 2
(-1835 4335);
DISPLAY 0.680851 (-1835 4335);
PAINT MONO (-1835 4335);
FORCEPROP 0 LASTPIN (-1825 4375) $PN 253
J 2
(-1835 4385);
DISPLAY 0.680851 (-1835 4385);
PAINT MONO (-1835 4385);
FORCEPROP 0 LASTPIN (-1825 4425) $PN 255
J 2
(-1835 4435);
DISPLAY 0.680851 (-1835 4435);
PAINT MONO (-1835 4435);
FORCEPROP 0 LASTPIN (-1825 4475) $PN 257
J 2
(-1835 4485);
DISPLAY 0.680851 (-1835 4485);
PAINT MONO (-1835 4485);
FORCEPROP 0 LASTPIN (-1825 4525) $PN 259
J 2
(-1835 4535);
DISPLAY 0.680851 (-1835 4535);
PAINT MONO (-1835 4535);
FORCEPROP 0 LASTPIN (-1825 4575) $PN 262
J 2
(-1835 4585);
DISPLAY 0.680851 (-1835 4585);
PAINT MONO (-1835 4585);
FORCEPROP 0 LASTPIN (-1825 4625) $PN 264
J 2
(-1835 4635);
DISPLAY 0.680851 (-1835 4635);
PAINT MONO (-1835 4635);
FORCEPROP 0 LASTPIN (-1825 4675) $PN 266
J 2
(-1835 4685);
DISPLAY 0.680851 (-1835 4685);
PAINT MONO (-1835 4685);
FORCEPROP 0 LASTPIN (-1825 4725) $PN 268
J 2
(-1835 4735);
DISPLAY 0.680851 (-1835 4735);
PAINT MONO (-1835 4735);
FORCEPROP 0 LASTPIN (-1825 4775) $PN 270
J 2
(-1835 4785);
DISPLAY 0.680851 (-1835 4785);
PAINT MONO (-1835 4785);
FORCEPROP 0 LASTPIN (-1825 4825) $PN 273
J 2
(-1835 4835);
DISPLAY 0.680851 (-1835 4835);
PAINT MONO (-1835 4835);
FORCEPROP 0 LASTPIN (-1825 4875) $PN 275
J 2
(-1835 4885);
DISPLAY 0.680851 (-1835 4885);
PAINT MONO (-1835 4885);
FORCEPROP 0 LASTPIN (-1825 4925) $PN 277
J 2
(-1835 4935);
DISPLAY 0.680851 (-1835 4935);
PAINT MONO (-1835 4935);
FORCEPROP 0 LASTPIN (-1825 4975) $PN 279
J 2
(-1835 4985);
DISPLAY 0.680851 (-1835 4985);
PAINT MONO (-1835 4985);
FORCEPROP 0 LASTPIN (-1825 5025) $PN 281
J 2
(-1835 5035);
DISPLAY 0.680851 (-1835 5035);
PAINT MONO (-1835 5035);
FORCEPROP 0 LASTPIN (-1825 5075) $PN 284
J 2
(-1835 5085);
DISPLAY 0.680851 (-1835 5085);
PAINT MONO (-1835 5085);
FORCEPROP 0 LASTPIN (-1825 5125) $PN 286
J 2
(-1835 5135);
DISPLAY 0.680851 (-1835 5135);
PAINT MONO (-1835 5135);
FORCEPROP 0 LASTPIN (-1825 5175) $PN 288
J 2
(-1835 5185);
DISPLAY 0.680851 (-1835 5185);
PAINT MONO (-1835 5185);
FORCEPROP 2 LAST PART_TYPE SMLF
J 0
(-1675 5750);
DISPLAY 1.021277 (-1675 5750);
FORCEPROP 2 LAST VALUE SCONN288_DDR506112002KQ
J 0
(-1675 5700);
DISPLAY 0.489362 (-1675 5700);
PAINT SKYBLUE (-1675 5700);
FORCEPROP 1 LAST MATERIAL IO
J 0
(-1675 5500);
DISPLAY 0.468085 (-1675 5500);
PAINT SKYBLUE (-1675 5500);
FORCEPROP 1 LAST PART_NUMBER DFHST8FS479
J 0
(-1675 5575);
DISPLAY 0.468085 (-1675 5575);
PAINT SKYBLUE (-1675 5575);
FORCEPROP 1 LAST CDS_LMAN_SYM_OUTLINE -450,1800,450,-1750
J 0
(-1225 3675);
DISPLAY 0.468085 (-1225 3675);
PAINT GREEN (-1225 3675);
DISPLAY INVISIBLE (-1225 3675);
FORCEPROP 1 LAST PATH I177
J 0
(-1225 3675);
DISPLAY 0.723404 (-1225 3675);
PAINT GREEN (-1225 3675);
DISPLAY INVISIBLE (-1225 3675);
FORCEPROP 1 LAST NEEDS_NO_SIZE TRUE
J 0
(-1225 3675);
DISPLAY 0.723404 (-1225 3675);
PAINT GREEN (-1225 3675);
DISPLAY INVISIBLE (-1225 3675);
FORCEPROP 2 LAST CDS_LIB pure_quanta
J 0
(-1225 3675);
DISPLAY INVISIBLE (-1225 3675);
FORCEADD OFFPAGE..6
(-8325 2825);
FORCEPROP 2 LAST $XR5 136 
J 0
(-9054 2825);
DISPLAY 0.638298 (-9054 2825);
PAINT MONO (-9054 2825);
FORCEPROP 2 LAST $XR4 96 
J 0
(-8934 2825);
DISPLAY 0.638298 (-8934 2825);
PAINT MONO (-8934 2825);
FORCEPROP 2 LAST $XR3 94 
J 0
(-8844 2825);
DISPLAY 0.638298 (-8844 2825);
PAINT MONO (-8844 2825);
FORCEPROP 2 LAST $XR2 93 
J 0
(-8754 2825);
DISPLAY 0.638298 (-8754 2825);
PAINT MONO (-8754 2825);
FORCEPROP 2 LAST $XR1 92 
J 0
(-8664 2825);
DISPLAY 0.638298 (-8664 2825);
PAINT MONO (-8664 2825);
FORCEPROP 2 LAST $XR0 91 
J 0
(-8574 2825);
DISPLAY 0.638298 (-8574 2825);
PAINT MONO (-8574 2825);
FORCEPROP 2 LAST PATH I179
J 0
(-8625 2875);
DISPLAY 1.021277 (-8625 2875);
DISPLAY INVISIBLE (-8625 2875);
FORCEPROP 1 LAST COMMENT_BODY TRUE
J 0
(-8225 2750);
DISPLAY 0.872340 (-8225 2750);
PAINT GREEN (-8225 2750);
DISPLAY INVISIBLE (-8225 2750);
FORCEPROP 1 LAST OFFPAGE TRUE
J 0
(-8000 2700);
DISPLAY 0.872340 (-8000 2700);
PAINT GREEN (-8000 2700);
DISPLAY INVISIBLE (-8000 2700);
FORCEPROP 2 LAST CDS_LIB mstr_standard
J 0
(-8325 2825);
DISPLAY 0.808511 (-8325 2825);
DISPLAY INVISIBLE (-8325 2825);
FORCEADD OFFPAGE..1
(-8325 4575);
FORCEPROP 2 LAST $XR0 20 
J 0
(-8546 4575);
DISPLAY 0.638298 (-8546 4575);
PAINT MONO (-8546 4575);
FORCEPROP 2 LAST PATH I18
J 0
(-8275 4650);
DISPLAY 1.021277 (-8275 4650);
DISPLAY INVISIBLE (-8275 4650);
FORCEPROP 1 LAST COMMENT_BODY TRUE
J 0
(-8200 4475);
DISPLAY 0.872340 (-8200 4475);
PAINT GREEN (-8200 4475);
DISPLAY INVISIBLE (-8200 4475);
FORCEPROP 1 LAST OFFPAGE TRUE
J 0
(-8000 4450);
DISPLAY 0.872340 (-8000 4450);
PAINT GREEN (-8000 4450);
DISPLAY INVISIBLE (-8000 4450);
FORCEPROP 2 LAST CDS_LIB mstr_standard
J 0
(-8325 4575);
DISPLAY 0.723404 (-8325 4575);
PAINT MONO (-8325 4575);
DISPLAY INVISIBLE (-8325 4575);
FORCEADD Q_CAP..1
R 2
(-8600 3200);
FORCEPROP 1 LAST LOCATION C128
J 2
(-8650 3300);
DISPLAY 0.489362 (-8650 3300);
PAINT SKYBLUE (-8650 3300);
FORCEPROP 0 LAST $SEC 1
J 0
(-8650 3350);
DISPLAY 0.680851 (-8650 3350);
PAINT MONO (-8650 3350);
DISPLAY INVISIBLE (-8650 3350);
FORCEPROP 0 LAST CDS_SEC 1
J 0
(-8650 3350);
DISPLAY 1.021277 (-8650 3350);
DISPLAY INVISIBLE (-8650 3350);
FORCEPROP 1 LASTPIN (-8600 3300) $PN 1
J 2
(-8610 3280);
DISPLAY 0.489362 (-8610 3280);
PAINT MONO (-8610 3280);
FORCEPROP 1 LASTPIN (-8600 3100) $PN 2
J 2
(-8610 3080);
DISPLAY 0.489362 (-8610 3080);
PAINT MONO (-8610 3080);
FORCEPROP 1 LAST MATERIAL X7R
J 2
(-8650 3100);
DISPLAY 0.489362 (-8650 3100);
PAINT SKYBLUE (-8650 3100);
FORCEPROP 1 LAST TOLERANCE 10%
J 2
(-8650 3150);
DISPLAY 0.489362 (-8650 3150);
PAINT SKYBLUE (-8650 3150);
FORCEPROP 1 LAST VALUE 0.1UF
J 2
(-8650 3250);
DISPLAY 0.489362 (-8650 3250);
PAINT SKYBLUE (-8650 3250);
FORCEPROP 1 LAST PART_NUMBER CH4104K1B00
J 2
(-8650 3050);
DISPLAY 0.489362 (-8650 3050);
PAINT SKYBLUE (-8650 3050);
FORCEPROP 1 LAST VOLTAGE 25V
J 2
(-8650 3200);
DISPLAY 0.489362 (-8650 3200);
PAINT SKYBLUE (-8650 3200);
FORCEPROP 1 LAST PACK_TYPE 0402
J 2
(-8650 3000);
DISPLAY 0.489362 (-8650 3000);
PAINT SKYBLUE (-8650 3000);
FORCEPROP 0 LAST BOM_COST MEM
J 2
(-8655 3345);
DISPLAY 0.595745 (-8655 3345);
PAINT MONO (-8655 3345);
DISPLAY INVISIBLE (-8655 3345);
FORCEPROP 2 LAST CDS_LIB pure_quanta
J 0
(-8600 3200);
DISPLAY INVISIBLE (-8600 3200);
FORCEPROP 1 LAST PATH I185
J 2
(-8650 3350);
DISPLAY 0.978723 (-8650 3350);
PAINT WHITE (-8650 3350);
DISPLAY INVISIBLE (-8650 3350);
FORCEPROP 0 LAST ROOM MEM_CH_A_CPU0_DIMM1
J 2
(-8655 3345);
DISPLAY 0.595745 (-8655 3345);
PAINT RED (-8655 3345);
DISPLAY INVISIBLE (-8655 3345);
FORCEADD GND..1
(-8600 2975);
FORCEPROP 3 LASTPIN (-8600 3025) SIG_NAME GND\g
J 0
(-8590 3035);
DISPLAY 0.659574 (-8590 3035);
PAINT MONO (-8590 3035);
DISPLAY INVISIBLE (-8590 3035);
FORCEPROP 2 LAST BOM_COST MEM
J 0
(-8575 3100);
DISPLAY 0.659574 (-8575 3100);
DISPLAY INVISIBLE (-8575 3100);
FORCEPROP 1 LAST SIZE 1B
J 0
(-8525 2925);
DISPLAY 0.723404 (-8525 2925);
PAINT GREEN (-8525 2925);
DISPLAY INVISIBLE (-8525 2925);
FORCEPROP 2 LAST CDS_LIB mstr_symbols
J 0
(-8600 2975);
DISPLAY 0.808511 (-8600 2975);
DISPLAY INVISIBLE (-8600 2975);
FORCEPROP 1 LAST BODY_TYPE PLUMBING
J 0
(-8645 2932);
DISPLAY 0.276596 (-8645 2932);
PAINT GREEN (-8645 2932);
DISPLAY INVISIBLE (-8645 2932);
FORCEPROP 1 LAST PATH I186
J 0
(-8525 2975);
DISPLAY 0.872340 (-8525 2975);
PAINT AQUA (-8525 2975);
DISPLAY INVISIBLE (-8525 2975);
FORCEPROP 1 LAST VOLTAGE 0
J 0
(-8620 3070);
DISPLAY 0.829787 (-8620 3070);
PAINT SKYBLUE (-8620 3070);
DISPLAY INVISIBLE (-8620 3070);
FORCEPROP 2 LAST ROOM MEM_EFGH_DECOUPLING_CAPS
J 0
(-8575 3050);
DISPLAY 0.659574 (-8575 3050);
PAINT RED (-8575 3050);
DISPLAY INVISIBLE (-8575 3050);
FORCEPROP 1 LAST HDL_POWER GND
J 0
(-8600 3125);
DISPLAY 0.723404 (-8600 3125);
PAINT GREEN (-8600 3125);
DISPLAY INVISIBLE (-8600 3125);
FORCEADD OFFPAGE..6
(-9025 2125);
FORCEPROP 2 LAST $XR5 81 
J 0
(-9274 2017);
DISPLAY 0.638298 (-9274 2017);
PAINT MONO (-9274 2017);
FORCEPROP 2 LAST $XR4 96 
J 0
(-9274 2197);
DISPLAY 0.638298 (-9274 2197);
PAINT MONO (-9274 2197);
FORCEPROP 2 LAST $XR3 94 
J 0
(-9274 2053);
DISPLAY 0.638298 (-9274 2053);
PAINT MONO (-9274 2053);
FORCEPROP 2 LAST $XR2 93 
J 0
(-9274 2161);
DISPLAY 0.638298 (-9274 2161);
PAINT MONO (-9274 2161);
FORCEPROP 2 LAST $XR1 92 
J 0
(-9274 2089);
DISPLAY 0.638298 (-9274 2089);
PAINT MONO (-9274 2089);
FORCEPROP 2 LAST $XR0 91 
J 0
(-9274 2125);
DISPLAY 0.638298 (-9274 2125);
PAINT MONO (-9274 2125);
FORCEPROP 2 LAST PATH I187
J 0
(-8975 2200);
DISPLAY 1.021277 (-8975 2200);
DISPLAY INVISIBLE (-8975 2200);
FORCEPROP 1 LAST COMMENT_BODY TRUE
J 0
(-8925 2050);
DISPLAY 0.872340 (-8925 2050);
PAINT GREEN (-8925 2050);
DISPLAY INVISIBLE (-8925 2050);
FORCEPROP 1 LAST OFFPAGE TRUE
J 0
(-8700 2000);
DISPLAY 0.872340 (-8700 2000);
PAINT GREEN (-8700 2000);
DISPLAY INVISIBLE (-8700 2000);
FORCEPROP 2 LAST CDS_LIB mstr_standard
J 0
(-9025 2125);
DISPLAY INVISIBLE (-9025 2125);
FORCEADD Q_RES..1
R 2
(-8475 2125);
FORCEPROP 1 LAST LOCATION R301
J 2
(-8425 2175);
DISPLAY 0.489362 (-8425 2175);
PAINT SKYBLUE (-8425 2175);
FORCEPROP 0 LAST $SEC 1
J 0
(-8425 2225);
DISPLAY 0.680851 (-8425 2225);
PAINT MONO (-8425 2225);
DISPLAY INVISIBLE (-8425 2225);
FORCEPROP 0 LAST CDS_SEC 1
J 0
(-8425 2225);
DISPLAY 1.021277 (-8425 2225);
DISPLAY INVISIBLE (-8425 2225);
FORCEPROP 1 LASTPIN (-8375 2125) $PN 1
J 2
(-8387 2137);
DISPLAY 0.489362 (-8387 2137);
PAINT MONO (-8387 2137);
FORCEPROP 1 LASTPIN (-8575 2125) $PN 2
J 2
(-8537 2137);
DISPLAY 0.489362 (-8537 2137);
PAINT MONO (-8537 2137);
FORCEPROP 1 LAST VALUE 0
J 0
(-8475 2075);
DISPLAY 0.489362 (-8475 2075);
PAINT SKYBLUE (-8475 2075);
FORCEPROP 2 LAST CDS_LIB pure_quanta
J 0
(-8475 2125);
DISPLAY INVISIBLE (-8475 2125);
FORCEPROP 2 LAST BOM_COST MEM
J 0
(-8500 2275);
DISPLAY 0.744681 (-8500 2275);
PAINT WHITE (-8500 2275);
DISPLAY INVISIBLE (-8500 2275);
FORCEPROP 1 LAST PATH I188
J 2
(-8425 2275);
DISPLAY 0.978723 (-8425 2275);
PAINT WHITE (-8425 2275);
DISPLAY INVISIBLE (-8425 2275);
FORCEPROP 1 LAST WATTAGE 1/16W
J 0
(-8400 2050);
DISPLAY 0.489362 (-8400 2050);
PAINT SKYBLUE (-8400 2050);
DISPLAY INVISIBLE (-8400 2050);
FORCEPROP 1 LAST MATERIAL CHIP
J 0
(-8650 2100);
DISPLAY 0.489362 (-8650 2100);
PAINT SKYBLUE (-8650 2100);
DISPLAY INVISIBLE (-8650 2100);
FORCEPROP 1 LAST TOLERANCE 5%
J 2
(-8350 2100);
DISPLAY 0.489362 (-8350 2100);
PAINT SKYBLUE (-8350 2100);
DISPLAY INVISIBLE (-8350 2100);
FORCEPROP 1 LAST PART_NUMBER CS00002JB38
J 0
(-8575 2175);
DISPLAY 0.489362 (-8575 2175);
PAINT SKYBLUE (-8575 2175);
DISPLAY INVISIBLE (-8575 2175);
FORCEPROP 1 LAST PACK_TYPE 0402LF
J 0
(-8650 2050);
DISPLAY 0.489362 (-8650 2050);
PAINT SKYBLUE (-8650 2050);
DISPLAY INVISIBLE (-8650 2050);
FORCEPROP 2 LAST ROOM RST_CPU0_PLD_TO_DIMM
J 0
(-8500 2225);
DISPLAY 0.744681 (-8500 2225);
PAINT RED (-8500 2225);
DISPLAY INVISIBLE (-8500 2225);
FORCEADD Q_RES..2
(-8350 2275);
FORCEPROP 1 LAST LOCATION R100
J 0
(-8305 2400);
DISPLAY 0.489362 (-8305 2400);
PAINT SKYBLUE (-8305 2400);
FORCEPROP 0 LAST $SEC 1
J 0
(-8300 2450);
DISPLAY 0.680851 (-8300 2450);
PAINT MONO (-8300 2450);
DISPLAY INVISIBLE (-8300 2450);
FORCEPROP 0 LAST CDS_SEC 1
J 0
(-8300 2450);
DISPLAY 1.021277 (-8300 2450);
DISPLAY INVISIBLE (-8300 2450);
FORCEPROP 1 LASTPIN (-8350 2375) $PN 1
J 0
(-8345 2337);
DISPLAY 0.489362 (-8345 2337);
PAINT MONO (-8345 2337);
FORCEPROP 1 LASTPIN (-8350 2175) $PN 2
J 0
(-8345 2185);
DISPLAY 0.489362 (-8345 2185);
PAINT MONO (-8345 2185);
FORCEPROP 1 LAST TOLERANCE 5%
J 0
(-8300 2325);
DISPLAY 0.489362 (-8300 2325);
PAINT SKYBLUE (-8300 2325);
FORCEPROP 1 LAST VALUE 1K
J 0
(-8305 2350);
DISPLAY 0.489362 (-8305 2350);
PAINT SKYBLUE (-8305 2350);
FORCEPROP 1 LAST PACK_TYPE 0402LF
J 0
(-8300 2225);
DISPLAY 0.489362 (-8300 2225);
PAINT SKYBLUE (-8300 2225);
FORCEPROP 1 LAST MATERIAL EMPTY
J 0
(-8300 2275);
DISPLAY 0.489362 (-8300 2275);
PAINT RED (-8300 2275);
FORCEPROP 1 LAST WATTAGE 1/16W
J 0
(-8300 2300);
DISPLAY 0.489362 (-8300 2300);
PAINT SKYBLUE (-8300 2300);
FORCEPROP 2 LAST CDS_LIB pure_quanta
J 0
(-8350 2275);
DISPLAY INVISIBLE (-8350 2275);
FORCEPROP 2 LAST BOM_COST MEM
J 0
(-8300 2450);
DISPLAY 0.808511 (-8300 2450);
DISPLAY INVISIBLE (-8300 2450);
FORCEPROP 1 LAST PATH I189
J 0
(-8300 2450);
DISPLAY 0.978723 (-8300 2450);
PAINT WHITE (-8300 2450);
DISPLAY INVISIBLE (-8300 2450);
FORCEPROP 1 LAST PART_NUMBER TMP_QCS21002JB34
J 0
(-8300 2250);
DISPLAY 0.489362 (-8300 2250);
PAINT SKYBLUE (-8300 2250);
DISPLAY INVISIBLE (-8300 2250);
FORCEPROP 2 LAST ROOM MEM_CH_A_CPU0_DIMM1
J 0
(-8300 2500);
DISPLAY 0.808511 (-8300 2500);
PAINT RED (-8300 2500);
DISPLAY INVISIBLE (-8300 2500);
FORCEADD OFFPAGE..1
(-8325 4525);
FORCEPROP 2 LAST $XR0 20 
J 0
(-8546 4525);
DISPLAY 0.638298 (-8546 4525);
PAINT MONO (-8546 4525);
FORCEPROP 2 LAST PATH I19
J 0
(-8275 4600);
DISPLAY 1.021277 (-8275 4600);
DISPLAY INVISIBLE (-8275 4600);
FORCEPROP 1 LAST COMMENT_BODY TRUE
J 0
(-8200 4425);
DISPLAY 0.872340 (-8200 4425);
PAINT GREEN (-8200 4425);
DISPLAY INVISIBLE (-8200 4425);
FORCEPROP 1 LAST OFFPAGE TRUE
J 0
(-8000 4400);
DISPLAY 0.872340 (-8000 4400);
PAINT GREEN (-8000 4400);
DISPLAY INVISIBLE (-8000 4400);
FORCEPROP 2 LAST CDS_LIB mstr_standard
J 0
(-8325 4525);
DISPLAY 0.808511 (-8325 4525);
DISPLAY INVISIBLE (-8325 4525);
FORCEADD VCC_CORE..1
(-8350 2450);
FORCEPROP 3 LASTPIN (-8350 2400) SIG_NAME P3V3_STBY\g
J 0
(-8340 2410);
DISPLAY 0.659574 (-8340 2410);
PAINT MONO (-8340 2410);
DISPLAY INVISIBLE (-8340 2410);
FORCEPROP 1 LAST HDL_POWER P3V3_STBY
J 1
(-8350 2500);
DISPLAY 0.489362 (-8350 2500);
PAINT GREEN (-8350 2500);
FORCEPROP 2 LAST CDS_LIB mstr_symbols
J 0
(-8350 2450);
DISPLAY INVISIBLE (-8350 2450);
FORCEPROP 1 LAST PATH I190
J 0
(-8300 2475);
DISPLAY 0.872340 (-8300 2475);
PAINT AQUA (-8300 2475);
DISPLAY INVISIBLE (-8300 2475);
FORCEPROP 0 LAST VOLTAGE 3.3
J 0
(-8625 2600);
DISPLAY 1.021277 (-8625 2600);
PAINT SKYBLUE (-8625 2600);
DISPLAY INVISIBLE (-8625 2600);
FORCEPROP 2 LAST ROOM PVCCINFAON_CPU0_CTRL
J 0
(-8350 2550);
DISPLAY 0.808511 (-8350 2550);
PAINT RED (-8350 2550);
DISPLAY INVISIBLE (-8350 2550);
FORCEADD TAP..1
(-3275 3200);
FORCEPROP 3 LASTPIN (-3325 3200) SIG_NAME M_K_CPU0_SB_DQS_DN<6>
J 0
(-3315 3210);
DISPLAY 0.659574 (-3315 3210);
PAINT MONO (-3315 3210);
DISPLAY INVISIBLE (-3315 3210);
FORCEPROP 1 LASTPIN (-3325 3200) BN 6
J 0
(-3337 3208);
DISPLAY 0.489362 (-3337 3208);
PAINT GREEN (-3337 3208);
FORCEPROP 2 LAST CDS_LIB mstr_standard
J 0
(-3275 3200);
DISPLAY 0.723404 (-3275 3200);
PAINT MONO (-3275 3200);
DISPLAY INVISIBLE (-3275 3200);
FORCEPROP 1 LAST BODY_TYPE PLUMBING
J 0
(-3275 3250);
DISPLAY 0.872340 (-3275 3250);
PAINT GREEN (-3275 3250);
DISPLAY INVISIBLE (-3275 3250);
FORCEPROP 1 LAST HDL_TAP TRUE
J 0
(-2950 3075);
DISPLAY 0.872340 (-2950 3075);
DISPLAY INVISIBLE (-2950 3075);
FORCEPROP 1 LAST PATH I191
J 0
(-3277 3200);
DISPLAY 0.872340 (-3277 3200);
PAINT GREEN (-3277 3200);
DISPLAY INVISIBLE (-3277 3200);
FORCEADD TAP..1
(-3475 3250);
FORCEPROP 3 LASTPIN (-3525 3250) SIG_NAME M_K_CPU0_SB_DQS_DP<6>
J 0
(-3515 3260);
DISPLAY 0.659574 (-3515 3260);
PAINT MONO (-3515 3260);
DISPLAY INVISIBLE (-3515 3260);
FORCEPROP 1 LASTPIN (-3525 3250) BN 6
J 0
(-3537 3258);
DISPLAY 0.489362 (-3537 3258);
PAINT GREEN (-3537 3258);
FORCEPROP 2 LAST CDS_LIB mstr_standard
J 0
(-3475 3250);
DISPLAY 0.723404 (-3475 3250);
PAINT MONO (-3475 3250);
DISPLAY INVISIBLE (-3475 3250);
FORCEPROP 1 LAST BODY_TYPE PLUMBING
J 0
(-3475 3300);
DISPLAY 0.872340 (-3475 3300);
PAINT GREEN (-3475 3300);
DISPLAY INVISIBLE (-3475 3300);
FORCEPROP 1 LAST HDL_TAP TRUE
J 0
(-3150 3125);
DISPLAY 0.872340 (-3150 3125);
DISPLAY INVISIBLE (-3150 3125);
FORCEPROP 1 LAST PATH I192
J 0
(-3477 3250);
DISPLAY 0.872340 (-3477 3250);
PAINT GREEN (-3477 3250);
DISPLAY INVISIBLE (-3477 3250);
FORCEADD TAP..1
(-3475 3350);
FORCEPROP 3 LASTPIN (-3525 3350) SIG_NAME M_K_CPU0_SB_DQS_DP<7>
J 0
(-3515 3360);
DISPLAY 0.659574 (-3515 3360);
PAINT MONO (-3515 3360);
DISPLAY INVISIBLE (-3515 3360);
FORCEPROP 1 LASTPIN (-3525 3350) BN 7
J 0
(-3537 3358);
DISPLAY 0.489362 (-3537 3358);
PAINT GREEN (-3537 3358);
FORCEPROP 2 LAST CDS_LIB mstr_standard
J 0
(-3475 3350);
DISPLAY 0.723404 (-3475 3350);
PAINT MONO (-3475 3350);
DISPLAY INVISIBLE (-3475 3350);
FORCEPROP 1 LAST BODY_TYPE PLUMBING
J 0
(-3475 3400);
DISPLAY 0.872340 (-3475 3400);
PAINT GREEN (-3475 3400);
DISPLAY INVISIBLE (-3475 3400);
FORCEPROP 1 LAST HDL_TAP TRUE
J 0
(-3150 3225);
DISPLAY 0.872340 (-3150 3225);
DISPLAY INVISIBLE (-3150 3225);
FORCEPROP 1 LAST PATH I193
J 0
(-3477 3350);
DISPLAY 0.872340 (-3477 3350);
PAINT GREEN (-3477 3350);
DISPLAY INVISIBLE (-3477 3350);
FORCEADD OFFPAGE..2
(-2475 4650);
FORCEPROP 2 LAST $XR0 20 
J 0
(-2286 4650);
DISPLAY 0.638298 (-2286 4650);
PAINT MONO (-2286 4650);
FORCEPROP 1 LAST COMMENT_BODY TRUE
J 0
(-2520 4555);
DISPLAY 0.872340 (-2520 4555);
PAINT GREEN (-2520 4555);
DISPLAY INVISIBLE (-2520 4555);
FORCEPROP 1 LAST OFFPAGE TRUE
J 0
(-2150 4525);
DISPLAY 0.723404 (-2150 4525);
PAINT GREEN (-2150 4525);
DISPLAY INVISIBLE (-2150 4525);
FORCEPROP 2 LAST CDS_LIB mstr_standard
J 0
(-2475 4650);
DISPLAY 0.723404 (-2475 4650);
PAINT MONO (-2475 4650);
DISPLAY INVISIBLE (-2475 4650);
FORCEPROP 2 LAST PATH I195
J 0
(-2275 4700);
DISPLAY 0.680851 (-2275 4700);
DISPLAY INVISIBLE (-2275 4700);
FORCEADD OFFPAGE..2
(-2475 4600);
FORCEPROP 2 LAST $XR0 20 
J 0
(-2286 4600);
DISPLAY 0.638298 (-2286 4600);
PAINT MONO (-2286 4600);
FORCEPROP 1 LAST COMMENT_BODY TRUE
J 0
(-2520 4505);
DISPLAY 0.872340 (-2520 4505);
PAINT GREEN (-2520 4505);
DISPLAY INVISIBLE (-2520 4505);
FORCEPROP 1 LAST OFFPAGE TRUE
J 0
(-2150 4475);
DISPLAY 0.723404 (-2150 4475);
PAINT GREEN (-2150 4475);
DISPLAY INVISIBLE (-2150 4475);
FORCEPROP 2 LAST CDS_LIB mstr_standard
J 0
(-2475 4600);
DISPLAY 0.723404 (-2475 4600);
PAINT MONO (-2475 4600);
DISPLAY INVISIBLE (-2475 4600);
FORCEPROP 2 LAST PATH I196
J 0
(-2275 4650);
DISPLAY 0.680851 (-2275 4650);
DISPLAY INVISIBLE (-2275 4650);
FORCEADD OFFPAGE..2
(-2475 3600);
FORCEPROP 2 LAST $XR0 20 
J 0
(-2286 3600);
DISPLAY 0.638298 (-2286 3600);
PAINT MONO (-2286 3600);
FORCEPROP 1 LAST COMMENT_BODY TRUE
J 0
(-2520 3505);
DISPLAY 0.872340 (-2520 3505);
PAINT GREEN (-2520 3505);
DISPLAY INVISIBLE (-2520 3505);
FORCEPROP 1 LAST OFFPAGE TRUE
J 0
(-2150 3475);
DISPLAY 0.723404 (-2150 3475);
PAINT GREEN (-2150 3475);
DISPLAY INVISIBLE (-2150 3475);
FORCEPROP 2 LAST CDS_LIB mstr_standard
J 0
(-2475 3600);
DISPLAY 0.723404 (-2475 3600);
PAINT MONO (-2475 3600);
DISPLAY INVISIBLE (-2475 3600);
FORCEPROP 2 LAST PATH I197
J 0
(-2275 3650);
DISPLAY 0.680851 (-2275 3650);
DISPLAY INVISIBLE (-2275 3650);
FORCEADD OFFPAGE..2
(-2475 3550);
FORCEPROP 2 LAST $XR0 20 
J 0
(-2286 3550);
DISPLAY 0.638298 (-2286 3550);
PAINT MONO (-2286 3550);
FORCEPROP 1 LAST COMMENT_BODY TRUE
J 0
(-2520 3455);
DISPLAY 0.872340 (-2520 3455);
PAINT GREEN (-2520 3455);
DISPLAY INVISIBLE (-2520 3455);
FORCEPROP 1 LAST OFFPAGE TRUE
J 0
(-2150 3425);
DISPLAY 0.723404 (-2150 3425);
PAINT GREEN (-2150 3425);
DISPLAY INVISIBLE (-2150 3425);
FORCEPROP 2 LAST CDS_LIB mstr_standard
J 0
(-2475 3550);
DISPLAY 0.723404 (-2475 3550);
PAINT MONO (-2475 3550);
DISPLAY INVISIBLE (-2475 3550);
FORCEPROP 2 LAST PATH I198
J 0
(-2275 3600);
DISPLAY 0.680851 (-2275 3600);
DISPLAY INVISIBLE (-2275 3600);
FORCEADD TAP..1
(-3275 4550);
FORCEPROP 3 LASTPIN (-3325 4550) SIG_NAME M_K_CPU0_SA_DQS_DN<9>
J 0
(-3315 4560);
DISPLAY 0.659574 (-3315 4560);
PAINT MONO (-3315 4560);
DISPLAY INVISIBLE (-3315 4560);
FORCEPROP 1 LASTPIN (-3325 4550) BN 9
J 0
(-3337 4558);
DISPLAY 0.489362 (-3337 4558);
PAINT GREEN (-3337 4558);
FORCEPROP 2 LAST CDS_LIB mstr_standard
J 0
(-3275 4550);
DISPLAY 0.723404 (-3275 4550);
PAINT MONO (-3275 4550);
DISPLAY INVISIBLE (-3275 4550);
FORCEPROP 1 LAST BODY_TYPE PLUMBING
J 0
(-3275 4600);
DISPLAY 0.872340 (-3275 4600);
PAINT GREEN (-3275 4600);
DISPLAY INVISIBLE (-3275 4600);
FORCEPROP 1 LAST HDL_TAP TRUE
J 0
(-2950 4425);
DISPLAY 0.872340 (-2950 4425);
DISPLAY INVISIBLE (-2950 4425);
FORCEPROP 1 LAST PATH I199
J 0
(-3277 4550);
DISPLAY 0.872340 (-3277 4550);
PAINT GREEN (-3277 4550);
DISPLAY INVISIBLE (-3277 4550);
FORCEADD OFFPAGE..1
(-8325 5025);
FORCEPROP 2 LAST $XR0 20 
J 0
(-8546 5025);
DISPLAY 0.638298 (-8546 5025);
PAINT MONO (-8546 5025);
FORCEPROP 2 LAST PATH I20
J 0
(-8275 5100);
DISPLAY 1.021277 (-8275 5100);
DISPLAY INVISIBLE (-8275 5100);
FORCEPROP 1 LAST COMMENT_BODY TRUE
J 0
(-8200 4925);
DISPLAY 0.872340 (-8200 4925);
PAINT GREEN (-8200 4925);
DISPLAY INVISIBLE (-8200 4925);
FORCEPROP 1 LAST OFFPAGE TRUE
J 0
(-8000 4900);
DISPLAY 0.872340 (-8000 4900);
PAINT GREEN (-8000 4900);
DISPLAY INVISIBLE (-8000 4900);
FORCEPROP 2 LAST CDS_LIB mstr_standard
J 0
(-8325 5025);
DISPLAY 0.723404 (-8325 5025);
PAINT MONO (-8325 5025);
DISPLAY INVISIBLE (-8325 5025);
FORCEADD TAP..1
(-3275 4450);
FORCEPROP 3 LASTPIN (-3325 4450) SIG_NAME M_K_CPU0_SA_DQS_DN<8>
J 0
(-3315 4460);
DISPLAY 0.659574 (-3315 4460);
PAINT MONO (-3315 4460);
DISPLAY INVISIBLE (-3315 4460);
FORCEPROP 1 LASTPIN (-3325 4450) BN 8
J 0
(-3337 4458);
DISPLAY 0.489362 (-3337 4458);
PAINT GREEN (-3337 4458);
FORCEPROP 2 LAST CDS_LIB mstr_standard
J 0
(-3275 4450);
DISPLAY 0.723404 (-3275 4450);
PAINT MONO (-3275 4450);
DISPLAY INVISIBLE (-3275 4450);
FORCEPROP 1 LAST BODY_TYPE PLUMBING
J 0
(-3275 4500);
DISPLAY 0.872340 (-3275 4500);
PAINT GREEN (-3275 4500);
DISPLAY INVISIBLE (-3275 4500);
FORCEPROP 1 LAST HDL_TAP TRUE
J 0
(-2950 4325);
DISPLAY 0.872340 (-2950 4325);
DISPLAY INVISIBLE (-2950 4325);
FORCEPROP 1 LAST PATH I200
J 0
(-3277 4450);
DISPLAY 0.872340 (-3277 4450);
PAINT GREEN (-3277 4450);
DISPLAY INVISIBLE (-3277 4450);
FORCEADD TAP..1
(-3475 4600);
FORCEPROP 3 LASTPIN (-3525 4600) SIG_NAME M_K_CPU0_SA_DQS_DP<9>
J 0
(-3515 4610);
DISPLAY 0.659574 (-3515 4610);
PAINT MONO (-3515 4610);
DISPLAY INVISIBLE (-3515 4610);
FORCEPROP 1 LASTPIN (-3525 4600) BN 9
J 0
(-3537 4608);
DISPLAY 0.489362 (-3537 4608);
PAINT GREEN (-3537 4608);
FORCEPROP 2 LAST CDS_LIB mstr_standard
J 0
(-3475 4600);
DISPLAY 0.723404 (-3475 4600);
PAINT MONO (-3475 4600);
DISPLAY INVISIBLE (-3475 4600);
FORCEPROP 1 LAST BODY_TYPE PLUMBING
J 0
(-3475 4650);
DISPLAY 0.872340 (-3475 4650);
PAINT GREEN (-3475 4650);
DISPLAY INVISIBLE (-3475 4650);
FORCEPROP 1 LAST HDL_TAP TRUE
J 0
(-3150 4475);
DISPLAY 0.872340 (-3150 4475);
DISPLAY INVISIBLE (-3150 4475);
FORCEPROP 1 LAST PATH I201
J 0
(-3477 4600);
DISPLAY 0.872340 (-3477 4600);
PAINT GREEN (-3477 4600);
DISPLAY INVISIBLE (-3477 4600);
FORCEADD TAP..1
(-3475 4400);
FORCEPROP 3 LASTPIN (-3525 4400) SIG_NAME M_K_CPU0_SA_DQS_DP<7>
J 0
(-3515 4410);
DISPLAY 0.659574 (-3515 4410);
PAINT MONO (-3515 4410);
DISPLAY INVISIBLE (-3515 4410);
FORCEPROP 1 LASTPIN (-3525 4400) BN 7
J 0
(-3537 4408);
DISPLAY 0.489362 (-3537 4408);
PAINT GREEN (-3537 4408);
FORCEPROP 2 LAST CDS_LIB mstr_standard
J 0
(-3475 4400);
DISPLAY 0.723404 (-3475 4400);
PAINT MONO (-3475 4400);
DISPLAY INVISIBLE (-3475 4400);
FORCEPROP 1 LAST BODY_TYPE PLUMBING
J 0
(-3475 4450);
DISPLAY 0.872340 (-3475 4450);
PAINT GREEN (-3475 4450);
DISPLAY INVISIBLE (-3475 4450);
FORCEPROP 1 LAST HDL_TAP TRUE
J 0
(-3150 4275);
DISPLAY 0.872340 (-3150 4275);
DISPLAY INVISIBLE (-3150 4275);
FORCEPROP 1 LAST PATH I202
J 0
(-3477 4400);
DISPLAY 0.872340 (-3477 4400);
PAINT GREEN (-3477 4400);
DISPLAY INVISIBLE (-3477 4400);
FORCEADD TAP..1
(-3475 4500);
FORCEPROP 3 LASTPIN (-3525 4500) SIG_NAME M_K_CPU0_SA_DQS_DP<8>
J 0
(-3515 4510);
DISPLAY 0.659574 (-3515 4510);
PAINT MONO (-3515 4510);
DISPLAY INVISIBLE (-3515 4510);
FORCEPROP 1 LASTPIN (-3525 4500) BN 8
J 0
(-3537 4508);
DISPLAY 0.489362 (-3537 4508);
PAINT GREEN (-3537 4508);
FORCEPROP 2 LAST CDS_LIB mstr_standard
J 0
(-3475 4500);
DISPLAY 0.723404 (-3475 4500);
PAINT MONO (-3475 4500);
DISPLAY INVISIBLE (-3475 4500);
FORCEPROP 1 LAST BODY_TYPE PLUMBING
J 0
(-3475 4550);
DISPLAY 0.872340 (-3475 4550);
PAINT GREEN (-3475 4550);
DISPLAY INVISIBLE (-3475 4550);
FORCEPROP 1 LAST HDL_TAP TRUE
J 0
(-3150 4375);
DISPLAY 0.872340 (-3150 4375);
DISPLAY INVISIBLE (-3150 4375);
FORCEPROP 1 LAST PATH I203
J 0
(-3477 4500);
DISPLAY 0.872340 (-3477 4500);
PAINT GREEN (-3477 4500);
DISPLAY INVISIBLE (-3477 4500);
FORCEADD TAP..1
(-3275 4350);
FORCEPROP 3 LASTPIN (-3325 4350) SIG_NAME M_K_CPU0_SA_DQS_DN<7>
J 0
(-3315 4360);
DISPLAY 0.659574 (-3315 4360);
PAINT MONO (-3315 4360);
DISPLAY INVISIBLE (-3315 4360);
FORCEPROP 1 LASTPIN (-3325 4350) BN 7
J 0
(-3337 4358);
DISPLAY 0.489362 (-3337 4358);
PAINT GREEN (-3337 4358);
FORCEPROP 2 LAST CDS_LIB mstr_standard
J 0
(-3275 4350);
DISPLAY 0.723404 (-3275 4350);
PAINT MONO (-3275 4350);
DISPLAY INVISIBLE (-3275 4350);
FORCEPROP 1 LAST BODY_TYPE PLUMBING
J 0
(-3275 4400);
DISPLAY 0.872340 (-3275 4400);
PAINT GREEN (-3275 4400);
DISPLAY INVISIBLE (-3275 4400);
FORCEPROP 1 LAST HDL_TAP TRUE
J 0
(-2950 4225);
DISPLAY 0.872340 (-2950 4225);
DISPLAY INVISIBLE (-2950 4225);
FORCEPROP 1 LAST PATH I204
J 0
(-3277 4350);
DISPLAY 0.872340 (-3277 4350);
PAINT GREEN (-3277 4350);
DISPLAY INVISIBLE (-3277 4350);
FORCEADD TAP..1
(-3275 4150);
FORCEPROP 3 LASTPIN (-3325 4150) SIG_NAME M_K_CPU0_SA_DQS_DN<5>
J 0
(-3315 4160);
DISPLAY 0.659574 (-3315 4160);
PAINT MONO (-3315 4160);
DISPLAY INVISIBLE (-3315 4160);
FORCEPROP 1 LASTPIN (-3325 4150) BN 5
J 0
(-3337 4158);
DISPLAY 0.489362 (-3337 4158);
PAINT GREEN (-3337 4158);
FORCEPROP 2 LAST CDS_LIB mstr_standard
J 0
(-3275 4150);
DISPLAY 0.723404 (-3275 4150);
PAINT MONO (-3275 4150);
DISPLAY INVISIBLE (-3275 4150);
FORCEPROP 1 LAST BODY_TYPE PLUMBING
J 0
(-3275 4200);
DISPLAY 0.872340 (-3275 4200);
PAINT GREEN (-3275 4200);
DISPLAY INVISIBLE (-3275 4200);
FORCEPROP 1 LAST HDL_TAP TRUE
J 0
(-2950 4025);
DISPLAY 0.872340 (-2950 4025);
DISPLAY INVISIBLE (-2950 4025);
FORCEPROP 1 LAST PATH I205
J 0
(-3277 4150);
DISPLAY 0.872340 (-3277 4150);
PAINT GREEN (-3277 4150);
DISPLAY INVISIBLE (-3277 4150);
FORCEADD TAP..1
(-3275 4250);
FORCEPROP 3 LASTPIN (-3325 4250) SIG_NAME M_K_CPU0_SA_DQS_DN<6>
J 0
(-3315 4260);
DISPLAY 0.659574 (-3315 4260);
PAINT MONO (-3315 4260);
DISPLAY INVISIBLE (-3315 4260);
FORCEPROP 1 LASTPIN (-3325 4250) BN 6
J 0
(-3337 4258);
DISPLAY 0.489362 (-3337 4258);
PAINT GREEN (-3337 4258);
FORCEPROP 2 LAST CDS_LIB mstr_standard
J 0
(-3275 4250);
DISPLAY 0.723404 (-3275 4250);
PAINT MONO (-3275 4250);
DISPLAY INVISIBLE (-3275 4250);
FORCEPROP 1 LAST BODY_TYPE PLUMBING
J 0
(-3275 4300);
DISPLAY 0.872340 (-3275 4300);
PAINT GREEN (-3275 4300);
DISPLAY INVISIBLE (-3275 4300);
FORCEPROP 1 LAST HDL_TAP TRUE
J 0
(-2950 4125);
DISPLAY 0.872340 (-2950 4125);
DISPLAY INVISIBLE (-2950 4125);
FORCEPROP 1 LAST PATH I206
J 0
(-3277 4250);
DISPLAY 0.872340 (-3277 4250);
PAINT GREEN (-3277 4250);
DISPLAY INVISIBLE (-3277 4250);
FORCEADD TAP..1
(-3275 4050);
FORCEPROP 3 LASTPIN (-3325 4050) SIG_NAME M_K_CPU0_SA_DQS_DN<4>
J 0
(-3315 4060);
DISPLAY 0.659574 (-3315 4060);
PAINT MONO (-3315 4060);
DISPLAY INVISIBLE (-3315 4060);
FORCEPROP 1 LASTPIN (-3325 4050) BN 4
J 0
(-3337 4058);
DISPLAY 0.489362 (-3337 4058);
PAINT GREEN (-3337 4058);
FORCEPROP 2 LAST CDS_LIB mstr_standard
J 0
(-3275 4050);
DISPLAY 0.723404 (-3275 4050);
PAINT MONO (-3275 4050);
DISPLAY INVISIBLE (-3275 4050);
FORCEPROP 1 LAST BODY_TYPE PLUMBING
J 0
(-3275 4100);
DISPLAY 0.872340 (-3275 4100);
PAINT GREEN (-3275 4100);
DISPLAY INVISIBLE (-3275 4100);
FORCEPROP 1 LAST HDL_TAP TRUE
J 0
(-2950 3925);
DISPLAY 0.872340 (-2950 3925);
DISPLAY INVISIBLE (-2950 3925);
FORCEPROP 1 LAST PATH I207
J 0
(-3277 4050);
DISPLAY 0.872340 (-3277 4050);
PAINT GREEN (-3277 4050);
DISPLAY INVISIBLE (-3277 4050);
FORCEADD TAP..1
(-3275 3950);
FORCEPROP 3 LASTPIN (-3325 3950) SIG_NAME M_K_CPU0_SA_DQS_DN<3>
J 0
(-3315 3960);
DISPLAY 0.659574 (-3315 3960);
PAINT MONO (-3315 3960);
DISPLAY INVISIBLE (-3315 3960);
FORCEPROP 1 LASTPIN (-3325 3950) BN 3
J 0
(-3337 3958);
DISPLAY 0.489362 (-3337 3958);
PAINT GREEN (-3337 3958);
FORCEPROP 2 LAST CDS_LIB mstr_standard
J 0
(-3275 3950);
DISPLAY 0.723404 (-3275 3950);
PAINT MONO (-3275 3950);
DISPLAY INVISIBLE (-3275 3950);
FORCEPROP 1 LAST BODY_TYPE PLUMBING
J 0
(-3275 4000);
DISPLAY 0.872340 (-3275 4000);
PAINT GREEN (-3275 4000);
DISPLAY INVISIBLE (-3275 4000);
FORCEPROP 1 LAST HDL_TAP TRUE
J 0
(-2950 3825);
DISPLAY 0.872340 (-2950 3825);
DISPLAY INVISIBLE (-2950 3825);
FORCEPROP 1 LAST PATH I208
J 0
(-3277 3950);
DISPLAY 0.872340 (-3277 3950);
PAINT GREEN (-3277 3950);
DISPLAY INVISIBLE (-3277 3950);
FORCEADD TAP..1
(-3275 3850);
FORCEPROP 3 LASTPIN (-3325 3850) SIG_NAME M_K_CPU0_SA_DQS_DN<2>
J 0
(-3315 3860);
DISPLAY 0.659574 (-3315 3860);
PAINT MONO (-3315 3860);
DISPLAY INVISIBLE (-3315 3860);
FORCEPROP 1 LASTPIN (-3325 3850) BN 2
J 0
(-3337 3858);
DISPLAY 0.489362 (-3337 3858);
PAINT GREEN (-3337 3858);
FORCEPROP 2 LAST CDS_LIB mstr_standard
J 0
(-3275 3850);
DISPLAY 0.723404 (-3275 3850);
PAINT MONO (-3275 3850);
DISPLAY INVISIBLE (-3275 3850);
FORCEPROP 1 LAST BODY_TYPE PLUMBING
J 0
(-3275 3900);
DISPLAY 0.872340 (-3275 3900);
PAINT GREEN (-3275 3900);
DISPLAY INVISIBLE (-3275 3900);
FORCEPROP 1 LAST HDL_TAP TRUE
J 0
(-2950 3725);
DISPLAY 0.872340 (-2950 3725);
DISPLAY INVISIBLE (-2950 3725);
FORCEPROP 1 LAST PATH I209
J 0
(-3277 3850);
DISPLAY 0.872340 (-3277 3850);
PAINT GREEN (-3277 3850);
DISPLAY INVISIBLE (-3277 3850);
FORCEADD OFFPAGE..1
(-8325 5425);
FORCEPROP 2 LAST $XR0 20 
J 0
(-8546 5425);
DISPLAY 0.638298 (-8546 5425);
PAINT MONO (-8546 5425);
FORCEPROP 2 LAST PATH I21
J 0
(-8275 5500);
DISPLAY 1.021277 (-8275 5500);
DISPLAY INVISIBLE (-8275 5500);
FORCEPROP 1 LAST COMMENT_BODY TRUE
J 0
(-8200 5325);
DISPLAY 0.872340 (-8200 5325);
PAINT GREEN (-8200 5325);
DISPLAY INVISIBLE (-8200 5325);
FORCEPROP 1 LAST OFFPAGE TRUE
J 0
(-8000 5300);
DISPLAY 0.872340 (-8000 5300);
PAINT GREEN (-8000 5300);
DISPLAY INVISIBLE (-8000 5300);
FORCEPROP 2 LAST CDS_LIB mstr_standard
J 0
(-8325 5425);
DISPLAY 0.723404 (-8325 5425);
PAINT MONO (-8325 5425);
DISPLAY INVISIBLE (-8325 5425);
FORCEADD TAP..1
(-3275 3650);
FORCEPROP 3 LASTPIN (-3325 3650) SIG_NAME M_K_CPU0_SA_DQS_DN<0>
J 0
(-3315 3660);
DISPLAY 0.659574 (-3315 3660);
PAINT MONO (-3315 3660);
DISPLAY INVISIBLE (-3315 3660);
FORCEPROP 1 LASTPIN (-3325 3650) BN 0
J 0
(-3337 3658);
DISPLAY 0.489362 (-3337 3658);
PAINT GREEN (-3337 3658);
FORCEPROP 2 LAST CDS_LIB mstr_standard
J 0
(-3275 3650);
DISPLAY 0.723404 (-3275 3650);
PAINT MONO (-3275 3650);
DISPLAY INVISIBLE (-3275 3650);
FORCEPROP 1 LAST BODY_TYPE PLUMBING
J 0
(-3275 3700);
DISPLAY 0.872340 (-3275 3700);
PAINT GREEN (-3275 3700);
DISPLAY INVISIBLE (-3275 3700);
FORCEPROP 1 LAST HDL_TAP TRUE
J 0
(-2950 3525);
DISPLAY 0.872340 (-2950 3525);
DISPLAY INVISIBLE (-2950 3525);
FORCEPROP 1 LAST PATH I210
J 0
(-3277 3650);
DISPLAY 0.872340 (-3277 3650);
PAINT GREEN (-3277 3650);
DISPLAY INVISIBLE (-3277 3650);
FORCEADD TAP..1
(-3275 3750);
FORCEPROP 3 LASTPIN (-3325 3750) SIG_NAME M_K_CPU0_SA_DQS_DN<1>
J 0
(-3315 3760);
DISPLAY 0.659574 (-3315 3760);
PAINT MONO (-3315 3760);
DISPLAY INVISIBLE (-3315 3760);
FORCEPROP 1 LASTPIN (-3325 3750) BN 1
J 0
(-3337 3758);
DISPLAY 0.489362 (-3337 3758);
PAINT GREEN (-3337 3758);
FORCEPROP 2 LAST CDS_LIB mstr_standard
J 0
(-3275 3750);
DISPLAY 0.723404 (-3275 3750);
PAINT MONO (-3275 3750);
DISPLAY INVISIBLE (-3275 3750);
FORCEPROP 1 LAST BODY_TYPE PLUMBING
J 0
(-3275 3800);
DISPLAY 0.872340 (-3275 3800);
PAINT GREEN (-3275 3800);
DISPLAY INVISIBLE (-3275 3800);
FORCEPROP 1 LAST HDL_TAP TRUE
J 0
(-2950 3625);
DISPLAY 0.872340 (-2950 3625);
DISPLAY INVISIBLE (-2950 3625);
FORCEPROP 1 LAST PATH I211
J 0
(-3277 3750);
DISPLAY 0.872340 (-3277 3750);
PAINT GREEN (-3277 3750);
DISPLAY INVISIBLE (-3277 3750);
FORCEADD TAP..1
(-3275 3500);
FORCEPROP 3 LASTPIN (-3325 3500) SIG_NAME M_K_CPU0_SB_DQS_DN<9>
J 0
(-3315 3510);
DISPLAY 0.659574 (-3315 3510);
PAINT MONO (-3315 3510);
DISPLAY INVISIBLE (-3315 3510);
FORCEPROP 1 LASTPIN (-3325 3500) BN 9
J 0
(-3337 3508);
DISPLAY 0.489362 (-3337 3508);
PAINT GREEN (-3337 3508);
FORCEPROP 2 LAST CDS_LIB mstr_standard
J 0
(-3275 3500);
DISPLAY 0.723404 (-3275 3500);
PAINT MONO (-3275 3500);
DISPLAY INVISIBLE (-3275 3500);
FORCEPROP 1 LAST BODY_TYPE PLUMBING
J 0
(-3275 3550);
DISPLAY 0.872340 (-3275 3550);
PAINT GREEN (-3275 3550);
DISPLAY INVISIBLE (-3275 3550);
FORCEPROP 1 LAST HDL_TAP TRUE
J 0
(-2950 3375);
DISPLAY 0.872340 (-2950 3375);
DISPLAY INVISIBLE (-2950 3375);
FORCEPROP 1 LAST PATH I212
J 0
(-3277 3500);
DISPLAY 0.872340 (-3277 3500);
PAINT GREEN (-3277 3500);
DISPLAY INVISIBLE (-3277 3500);
FORCEADD TAP..1
(-3275 3400);
FORCEPROP 3 LASTPIN (-3325 3400) SIG_NAME M_K_CPU0_SB_DQS_DN<8>
J 0
(-3315 3410);
DISPLAY 0.659574 (-3315 3410);
PAINT MONO (-3315 3410);
DISPLAY INVISIBLE (-3315 3410);
FORCEPROP 1 LASTPIN (-3325 3400) BN 8
J 0
(-3337 3408);
DISPLAY 0.489362 (-3337 3408);
PAINT GREEN (-3337 3408);
FORCEPROP 2 LAST CDS_LIB mstr_standard
J 0
(-3275 3400);
DISPLAY 0.723404 (-3275 3400);
PAINT MONO (-3275 3400);
DISPLAY INVISIBLE (-3275 3400);
FORCEPROP 1 LAST BODY_TYPE PLUMBING
J 0
(-3275 3450);
DISPLAY 0.872340 (-3275 3450);
PAINT GREEN (-3275 3450);
DISPLAY INVISIBLE (-3275 3450);
FORCEPROP 1 LAST HDL_TAP TRUE
J 0
(-2950 3275);
DISPLAY 0.872340 (-2950 3275);
DISPLAY INVISIBLE (-2950 3275);
FORCEPROP 1 LAST PATH I213
J 0
(-3277 3400);
DISPLAY 0.872340 (-3277 3400);
PAINT GREEN (-3277 3400);
DISPLAY INVISIBLE (-3277 3400);
FORCEADD TAP..1
(-3475 4300);
FORCEPROP 3 LASTPIN (-3525 4300) SIG_NAME M_K_CPU0_SA_DQS_DP<6>
J 0
(-3515 4310);
DISPLAY 0.659574 (-3515 4310);
PAINT MONO (-3515 4310);
DISPLAY INVISIBLE (-3515 4310);
FORCEPROP 1 LASTPIN (-3525 4300) BN 6
J 0
(-3537 4308);
DISPLAY 0.489362 (-3537 4308);
PAINT GREEN (-3537 4308);
FORCEPROP 2 LAST CDS_LIB mstr_standard
J 0
(-3475 4300);
DISPLAY 0.723404 (-3475 4300);
PAINT MONO (-3475 4300);
DISPLAY INVISIBLE (-3475 4300);
FORCEPROP 1 LAST BODY_TYPE PLUMBING
J 0
(-3475 4350);
DISPLAY 0.872340 (-3475 4350);
PAINT GREEN (-3475 4350);
DISPLAY INVISIBLE (-3475 4350);
FORCEPROP 1 LAST HDL_TAP TRUE
J 0
(-3150 4175);
DISPLAY 0.872340 (-3150 4175);
DISPLAY INVISIBLE (-3150 4175);
FORCEPROP 1 LAST PATH I214
J 0
(-3477 4300);
DISPLAY 0.872340 (-3477 4300);
PAINT GREEN (-3477 4300);
DISPLAY INVISIBLE (-3477 4300);
FORCEADD TAP..1
(-3475 4200);
FORCEPROP 3 LASTPIN (-3525 4200) SIG_NAME M_K_CPU0_SA_DQS_DP<5>
J 0
(-3515 4210);
DISPLAY 0.659574 (-3515 4210);
PAINT MONO (-3515 4210);
DISPLAY INVISIBLE (-3515 4210);
FORCEPROP 1 LASTPIN (-3525 4200) BN 5
J 0
(-3537 4208);
DISPLAY 0.489362 (-3537 4208);
PAINT GREEN (-3537 4208);
FORCEPROP 2 LAST CDS_LIB mstr_standard
J 0
(-3475 4200);
DISPLAY 0.723404 (-3475 4200);
PAINT MONO (-3475 4200);
DISPLAY INVISIBLE (-3475 4200);
FORCEPROP 1 LAST BODY_TYPE PLUMBING
J 0
(-3475 4250);
DISPLAY 0.872340 (-3475 4250);
PAINT GREEN (-3475 4250);
DISPLAY INVISIBLE (-3475 4250);
FORCEPROP 1 LAST HDL_TAP TRUE
J 0
(-3150 4075);
DISPLAY 0.872340 (-3150 4075);
DISPLAY INVISIBLE (-3150 4075);
FORCEPROP 1 LAST PATH I215
J 0
(-3477 4200);
DISPLAY 0.872340 (-3477 4200);
PAINT GREEN (-3477 4200);
DISPLAY INVISIBLE (-3477 4200);
FORCEADD TAP..1
(-3475 4100);
FORCEPROP 3 LASTPIN (-3525 4100) SIG_NAME M_K_CPU0_SA_DQS_DP<4>
J 0
(-3515 4110);
DISPLAY 0.659574 (-3515 4110);
PAINT MONO (-3515 4110);
DISPLAY INVISIBLE (-3515 4110);
FORCEPROP 1 LASTPIN (-3525 4100) BN 4
J 0
(-3537 4108);
DISPLAY 0.489362 (-3537 4108);
PAINT GREEN (-3537 4108);
FORCEPROP 2 LAST CDS_LIB mstr_standard
J 0
(-3475 4100);
DISPLAY 0.723404 (-3475 4100);
PAINT MONO (-3475 4100);
DISPLAY INVISIBLE (-3475 4100);
FORCEPROP 1 LAST BODY_TYPE PLUMBING
J 0
(-3475 4150);
DISPLAY 0.872340 (-3475 4150);
PAINT GREEN (-3475 4150);
DISPLAY INVISIBLE (-3475 4150);
FORCEPROP 1 LAST HDL_TAP TRUE
J 0
(-3150 3975);
DISPLAY 0.872340 (-3150 3975);
DISPLAY INVISIBLE (-3150 3975);
FORCEPROP 1 LAST PATH I216
J 0
(-3477 4100);
DISPLAY 0.872340 (-3477 4100);
PAINT GREEN (-3477 4100);
DISPLAY INVISIBLE (-3477 4100);
FORCEADD TAP..1
(-3475 3900);
FORCEPROP 3 LASTPIN (-3525 3900) SIG_NAME M_K_CPU0_SA_DQS_DP<2>
J 0
(-3515 3910);
DISPLAY 0.659574 (-3515 3910);
PAINT MONO (-3515 3910);
DISPLAY INVISIBLE (-3515 3910);
FORCEPROP 1 LASTPIN (-3525 3900) BN 2
J 0
(-3537 3908);
DISPLAY 0.489362 (-3537 3908);
PAINT GREEN (-3537 3908);
FORCEPROP 2 LAST CDS_LIB mstr_standard
J 0
(-3475 3900);
DISPLAY 0.723404 (-3475 3900);
PAINT MONO (-3475 3900);
DISPLAY INVISIBLE (-3475 3900);
FORCEPROP 1 LAST BODY_TYPE PLUMBING
J 0
(-3475 3950);
DISPLAY 0.872340 (-3475 3950);
PAINT GREEN (-3475 3950);
DISPLAY INVISIBLE (-3475 3950);
FORCEPROP 1 LAST HDL_TAP TRUE
J 0
(-3150 3775);
DISPLAY 0.872340 (-3150 3775);
DISPLAY INVISIBLE (-3150 3775);
FORCEPROP 1 LAST PATH I217
J 0
(-3477 3900);
DISPLAY 0.872340 (-3477 3900);
PAINT GREEN (-3477 3900);
DISPLAY INVISIBLE (-3477 3900);
FORCEADD TAP..1
(-3475 4000);
FORCEPROP 3 LASTPIN (-3525 4000) SIG_NAME M_K_CPU0_SA_DQS_DP<3>
J 0
(-3515 4010);
DISPLAY 0.659574 (-3515 4010);
PAINT MONO (-3515 4010);
DISPLAY INVISIBLE (-3515 4010);
FORCEPROP 1 LASTPIN (-3525 4000) BN 3
J 0
(-3537 4008);
DISPLAY 0.489362 (-3537 4008);
PAINT GREEN (-3537 4008);
FORCEPROP 2 LAST CDS_LIB mstr_standard
J 0
(-3475 4000);
DISPLAY 0.723404 (-3475 4000);
PAINT MONO (-3475 4000);
DISPLAY INVISIBLE (-3475 4000);
FORCEPROP 1 LAST BODY_TYPE PLUMBING
J 0
(-3475 4050);
DISPLAY 0.872340 (-3475 4050);
PAINT GREEN (-3475 4050);
DISPLAY INVISIBLE (-3475 4050);
FORCEPROP 1 LAST HDL_TAP TRUE
J 0
(-3150 3875);
DISPLAY 0.872340 (-3150 3875);
DISPLAY INVISIBLE (-3150 3875);
FORCEPROP 1 LAST PATH I218
J 0
(-3477 4000);
DISPLAY 0.872340 (-3477 4000);
PAINT GREEN (-3477 4000);
DISPLAY INVISIBLE (-3477 4000);
FORCEADD TAP..1
(-3475 3800);
FORCEPROP 3 LASTPIN (-3525 3800) SIG_NAME M_K_CPU0_SA_DQS_DP<1>
J 0
(-3515 3810);
DISPLAY 0.659574 (-3515 3810);
PAINT MONO (-3515 3810);
DISPLAY INVISIBLE (-3515 3810);
FORCEPROP 1 LASTPIN (-3525 3800) BN 1
J 0
(-3537 3808);
DISPLAY 0.489362 (-3537 3808);
PAINT GREEN (-3537 3808);
FORCEPROP 2 LAST CDS_LIB mstr_standard
J 0
(-3475 3800);
DISPLAY 0.723404 (-3475 3800);
PAINT MONO (-3475 3800);
DISPLAY INVISIBLE (-3475 3800);
FORCEPROP 1 LAST BODY_TYPE PLUMBING
J 0
(-3475 3850);
DISPLAY 0.872340 (-3475 3850);
PAINT GREEN (-3475 3850);
DISPLAY INVISIBLE (-3475 3850);
FORCEPROP 1 LAST HDL_TAP TRUE
J 0
(-3150 3675);
DISPLAY 0.872340 (-3150 3675);
DISPLAY INVISIBLE (-3150 3675);
FORCEPROP 1 LAST PATH I219
J 0
(-3477 3800);
DISPLAY 0.872340 (-3477 3800);
PAINT GREEN (-3477 3800);
DISPLAY INVISIBLE (-3477 3800);
FORCEADD SCONN288_DDR506112002KQ..1
(-6875 3625);
FORCEPROP 1 LAST LOCATION J20
J 0
(-7325 5700);
DISPLAY 0.468085 (-7325 5700);
PAINT SKYBLUE (-7325 5700);
FORCEPROP 0 LAST $SEC 1
J 0
(-7325 5850);
DISPLAY 0.680851 (-7325 5850);
PAINT MONO (-7325 5850);
DISPLAY INVISIBLE (-7325 5850);
FORCEPROP 2 LAST CDS_SEC 1
J 0
(-7325 5850);
DISPLAY 1.021277 (-7325 5850);
DISPLAY INVISIBLE (-7325 5850);
FORCEPROP 0 LASTPIN (-7475 3025) $PN 62
J 2
(-7485 3035);
DISPLAY 0.680851 (-7485 3035);
PAINT MONO (-7485 3035);
FORCEPROP 0 LASTPIN (-7475 5075) $PN 66
J 2
(-7485 5085);
DISPLAY 0.680851 (-7485 5085);
PAINT MONO (-7485 5085);
FORCEPROP 0 LASTPIN (-7475 4675) $PN 76
J 2
(-7485 4685);
DISPLAY 0.680851 (-7485 4685);
PAINT MONO (-7485 4685);
FORCEPROP 0 LASTPIN (-7475 5125) $PN 211
J 2
(-7485 5135);
DISPLAY 0.680851 (-7485 5135);
PAINT MONO (-7485 5135);
FORCEPROP 0 LASTPIN (-7475 4725) $PN 221
J 2
(-7485 4735);
DISPLAY 0.680851 (-7485 4735);
PAINT MONO (-7485 4735);
FORCEPROP 0 LASTPIN (-7475 5175) $PN 68
J 2
(-7485 5185);
DISPLAY 0.680851 (-7485 5185);
PAINT MONO (-7485 5185);
FORCEPROP 0 LASTPIN (-7475 4775) $PN 78
J 2
(-7485 4785);
DISPLAY 0.680851 (-7485 4785);
PAINT MONO (-7485 4785);
FORCEPROP 0 LASTPIN (-7475 5225) $PN 213
J 2
(-7485 5235);
DISPLAY 0.680851 (-7485 5235);
PAINT MONO (-7485 5235);
FORCEPROP 0 LASTPIN (-7475 4825) $PN 223
J 2
(-7485 4835);
DISPLAY 0.680851 (-7485 4835);
PAINT MONO (-7485 4835);
FORCEPROP 0 LASTPIN (-7475 5275) $PN 70
J 2
(-7485 5285);
DISPLAY 0.680851 (-7485 5285);
PAINT MONO (-7485 5285);
FORCEPROP 0 LASTPIN (-7475 4875) $PN 80
J 2
(-7485 4885);
DISPLAY 0.680851 (-7485 4885);
PAINT MONO (-7485 4885);
FORCEPROP 0 LASTPIN (-7475 5325) $PN 215
J 2
(-7485 5335);
DISPLAY 0.680851 (-7485 5335);
PAINT MONO (-7485 5335);
FORCEPROP 0 LASTPIN (-7475 4925) $PN 225
J 2
(-7485 4935);
DISPLAY 0.680851 (-7485 4935);
PAINT MONO (-7485 4935);
FORCEPROP 0 LASTPIN (-7475 5375) $PN 72
J 2
(-7485 5385);
DISPLAY 0.680851 (-7485 5385);
PAINT MONO (-7485 5385);
FORCEPROP 0 LASTPIN (-7475 4975) $PN 82
J 2
(-7485 4985);
DISPLAY 0.680851 (-7485 4985);
PAINT MONO (-7485 4985);
FORCEPROP 0 LASTPIN (-7475 3625) $PN 51
J 2
(-7485 3635);
DISPLAY 0.680851 (-7485 3635);
PAINT MONO (-7485 3635);
FORCEPROP 0 LASTPIN (-7475 3175) $PN 96
J 2
(-7485 3185);
DISPLAY 0.680851 (-7485 3185);
PAINT MONO (-7485 3185);
FORCEPROP 0 LASTPIN (-7475 3675) $PN 53
J 2
(-7485 3685);
DISPLAY 0.680851 (-7485 3685);
PAINT MONO (-7485 3685);
FORCEPROP 0 LASTPIN (-7475 3225) $PN 98
J 2
(-7485 3235);
DISPLAY 0.680851 (-7485 3235);
PAINT MONO (-7485 3235);
FORCEPROP 0 LASTPIN (-7475 3725) $PN 196
J 2
(-7485 3735);
DISPLAY 0.680851 (-7485 3735);
PAINT MONO (-7485 3735);
FORCEPROP 0 LASTPIN (-7475 3275) $PN 241
J 2
(-7485 3285);
DISPLAY 0.680851 (-7485 3285);
PAINT MONO (-7485 3285);
FORCEPROP 0 LASTPIN (-7475 3775) $PN 198
J 2
(-7485 3785);
DISPLAY 0.680851 (-7485 3785);
PAINT MONO (-7485 3785);
FORCEPROP 0 LASTPIN (-7475 3325) $PN 243
J 2
(-7485 3335);
DISPLAY 0.680851 (-7485 3335);
PAINT MONO (-7485 3335);
FORCEPROP 0 LASTPIN (-7475 3825) $PN 58
J 2
(-7485 3835);
DISPLAY 0.680851 (-7485 3835);
PAINT MONO (-7485 3835);
FORCEPROP 0 LASTPIN (-7475 3375) $PN 89
J 2
(-7485 3385);
DISPLAY 0.680851 (-7485 3385);
PAINT MONO (-7485 3385);
FORCEPROP 0 LASTPIN (-7475 3875) $PN 60
J 2
(-7485 3885);
DISPLAY 0.680851 (-7485 3885);
PAINT MONO (-7485 3885);
FORCEPROP 0 LASTPIN (-7475 3425) $PN 91
J 2
(-7485 3435);
DISPLAY 0.680851 (-7485 3435);
PAINT MONO (-7485 3435);
FORCEPROP 0 LASTPIN (-7475 3925) $PN 203
J 2
(-7485 3935);
DISPLAY 0.680851 (-7485 3935);
PAINT MONO (-7485 3935);
FORCEPROP 0 LASTPIN (-7475 3475) $PN 234
J 2
(-7485 3485);
DISPLAY 0.680851 (-7485 3485);
PAINT MONO (-7485 3485);
FORCEPROP 0 LASTPIN (-7475 3975) $PN 205
J 2
(-7485 3985);
DISPLAY 0.680851 (-7485 3985);
PAINT MONO (-7485 3985);
FORCEPROP 0 LASTPIN (-7475 3525) $PN 236
J 2
(-7485 3535);
DISPLAY 0.680851 (-7485 3535);
PAINT MONO (-7485 3535);
FORCEPROP 0 LASTPIN (-7475 4075) $PN 218
J 2
(-7485 4085);
DISPLAY 0.680851 (-7485 4085);
PAINT MONO (-7485 4085);
FORCEPROP 0 LASTPIN (-7475 4125) $PN 217
J 2
(-7485 4135);
DISPLAY 0.680851 (-7485 4135);
PAINT MONO (-7485 4135);
FORCEPROP 0 LASTPIN (-7475 4375) $PN 64
J 2
(-7485 4385);
DISPLAY 0.680851 (-7485 4385);
PAINT MONO (-7485 4385);
FORCEPROP 0 LASTPIN (-7475 4225) $PN 84
J 2
(-7485 4235);
DISPLAY 0.680851 (-7485 4235);
PAINT MONO (-7485 4235);
FORCEPROP 0 LASTPIN (-7475 4425) $PN 209
J 2
(-7485 4435);
DISPLAY 0.680851 (-7485 4435);
PAINT MONO (-7485 4435);
FORCEPROP 0 LASTPIN (-7475 4275) $PN 229
J 2
(-7485 4285);
DISPLAY 0.680851 (-7485 4285);
PAINT MONO (-7485 4285);
FORCEPROP 0 LASTPIN (-6275 3825) $PN 7
J 0
(-6265 3835);
DISPLAY 0.680851 (-6265 3835);
PAINT MONO (-6265 3835);
FORCEPROP 0 LASTPIN (-6275 2175) $PN 100
J 0
(-6265 2185);
DISPLAY 0.680851 (-6265 2185);
PAINT MONO (-6265 2185);
FORCEPROP 0 LASTPIN (-6275 3875) $PN 9
J 0
(-6265 3885);
DISPLAY 0.680851 (-6265 3885);
PAINT MONO (-6265 3885);
FORCEPROP 0 LASTPIN (-6275 2225) $PN 102
J 0
(-6265 2235);
DISPLAY 0.680851 (-6265 2235);
PAINT MONO (-6265 2235);
FORCEPROP 0 LASTPIN (-6275 3925) $PN 152
J 0
(-6265 3935);
DISPLAY 0.680851 (-6265 3935);
PAINT MONO (-6265 3935);
FORCEPROP 0 LASTPIN (-6275 2275) $PN 245
J 0
(-6265 2285);
DISPLAY 0.680851 (-6265 2285);
PAINT MONO (-6265 2285);
FORCEPROP 0 LASTPIN (-6275 3975) $PN 154
J 0
(-6265 3985);
DISPLAY 0.680851 (-6265 3985);
PAINT MONO (-6265 3985);
FORCEPROP 0 LASTPIN (-6275 2325) $PN 247
J 0
(-6265 2335);
DISPLAY 0.680851 (-6265 2335);
PAINT MONO (-6265 2335);
FORCEPROP 0 LASTPIN (-6275 4025) $PN 14
J 0
(-6265 4035);
DISPLAY 0.680851 (-6265 4035);
PAINT MONO (-6265 4035);
FORCEPROP 0 LASTPIN (-6275 2375) $PN 107
J 0
(-6265 2385);
DISPLAY 0.680851 (-6265 2385);
PAINT MONO (-6265 2385);
FORCEPROP 0 LASTPIN (-6275 4075) $PN 16
J 0
(-6265 4085);
DISPLAY 0.680851 (-6265 4085);
PAINT MONO (-6265 4085);
FORCEPROP 0 LASTPIN (-6275 2425) $PN 109
J 0
(-6265 2435);
DISPLAY 0.680851 (-6265 2435);
PAINT MONO (-6265 2435);
FORCEPROP 0 LASTPIN (-6275 4125) $PN 159
J 0
(-6265 4135);
DISPLAY 0.680851 (-6265 4135);
PAINT MONO (-6265 4135);
FORCEPROP 0 LASTPIN (-6275 2475) $PN 252
J 0
(-6265 2485);
DISPLAY 0.680851 (-6265 2485);
PAINT MONO (-6265 2485);
FORCEPROP 0 LASTPIN (-6275 4175) $PN 161
J 0
(-6265 4185);
DISPLAY 0.680851 (-6265 4185);
PAINT MONO (-6265 4185);
FORCEPROP 0 LASTPIN (-6275 2525) $PN 254
J 0
(-6265 2535);
DISPLAY 0.680851 (-6265 2535);
PAINT MONO (-6265 2535);
FORCEPROP 0 LASTPIN (-6275 4225) $PN 18
J 0
(-6265 4235);
DISPLAY 0.680851 (-6265 4235);
PAINT MONO (-6265 4235);
FORCEPROP 0 LASTPIN (-6275 2575) $PN 111
J 0
(-6265 2585);
DISPLAY 0.680851 (-6265 2585);
PAINT MONO (-6265 2585);
FORCEPROP 0 LASTPIN (-6275 4275) $PN 20
J 0
(-6265 4285);
DISPLAY 0.680851 (-6265 4285);
PAINT MONO (-6265 4285);
FORCEPROP 0 LASTPIN (-6275 2625) $PN 113
J 0
(-6265 2635);
DISPLAY 0.680851 (-6265 2635);
PAINT MONO (-6265 2635);
FORCEPROP 0 LASTPIN (-6275 4325) $PN 163
J 0
(-6265 4335);
DISPLAY 0.680851 (-6265 4335);
PAINT MONO (-6265 4335);
FORCEPROP 0 LASTPIN (-6275 2675) $PN 256
J 0
(-6265 2685);
DISPLAY 0.680851 (-6265 2685);
PAINT MONO (-6265 2685);
FORCEPROP 0 LASTPIN (-6275 4375) $PN 165
J 0
(-6265 4385);
DISPLAY 0.680851 (-6265 4385);
PAINT MONO (-6265 4385);
FORCEPROP 0 LASTPIN (-6275 2725) $PN 258
J 0
(-6265 2735);
DISPLAY 0.680851 (-6265 2735);
PAINT MONO (-6265 2735);
FORCEPROP 0 LASTPIN (-6275 4425) $PN 25
J 0
(-6265 4435);
DISPLAY 0.680851 (-6265 4435);
PAINT MONO (-6265 4435);
FORCEPROP 0 LASTPIN (-6275 2775) $PN 118
J 0
(-6265 2785);
DISPLAY 0.680851 (-6265 2785);
PAINT MONO (-6265 2785);
FORCEPROP 0 LASTPIN (-6275 4475) $PN 27
J 0
(-6265 4485);
DISPLAY 0.680851 (-6265 4485);
PAINT MONO (-6265 4485);
FORCEPROP 0 LASTPIN (-6275 2825) $PN 120
J 0
(-6265 2835);
DISPLAY 0.680851 (-6265 2835);
PAINT MONO (-6265 2835);
FORCEPROP 0 LASTPIN (-6275 4525) $PN 170
J 0
(-6265 4535);
DISPLAY 0.680851 (-6265 4535);
PAINT MONO (-6265 4535);
FORCEPROP 0 LASTPIN (-6275 2875) $PN 263
J 0
(-6265 2885);
DISPLAY 0.680851 (-6265 2885);
PAINT MONO (-6265 2885);
FORCEPROP 0 LASTPIN (-6275 4575) $PN 172
J 0
(-6265 4585);
DISPLAY 0.680851 (-6265 4585);
PAINT MONO (-6265 4585);
FORCEPROP 0 LASTPIN (-6275 2925) $PN 265
J 0
(-6265 2935);
DISPLAY 0.680851 (-6265 2935);
PAINT MONO (-6265 2935);
FORCEPROP 0 LASTPIN (-6275 4625) $PN 29
J 0
(-6265 4635);
DISPLAY 0.680851 (-6265 4635);
PAINT MONO (-6265 4635);
FORCEPROP 0 LASTPIN (-6275 2975) $PN 122
J 0
(-6265 2985);
DISPLAY 0.680851 (-6265 2985);
PAINT MONO (-6265 2985);
FORCEPROP 0 LASTPIN (-6275 4675) $PN 31
J 0
(-6265 4685);
DISPLAY 0.680851 (-6265 4685);
PAINT MONO (-6265 4685);
FORCEPROP 0 LASTPIN (-6275 3025) $PN 124
J 0
(-6265 3035);
DISPLAY 0.680851 (-6265 3035);
PAINT MONO (-6265 3035);
FORCEPROP 0 LASTPIN (-6275 4725) $PN 174
J 0
(-6265 4735);
DISPLAY 0.680851 (-6265 4735);
PAINT MONO (-6265 4735);
FORCEPROP 0 LASTPIN (-6275 3075) $PN 267
J 0
(-6265 3085);
DISPLAY 0.680851 (-6265 3085);
PAINT MONO (-6265 3085);
FORCEPROP 0 LASTPIN (-6275 4775) $PN 176
J 0
(-6265 4785);
DISPLAY 0.680851 (-6265 4785);
PAINT MONO (-6265 4785);
FORCEPROP 0 LASTPIN (-6275 3125) $PN 269
J 0
(-6265 3135);
DISPLAY 0.680851 (-6265 3135);
PAINT MONO (-6265 3135);
FORCEPROP 0 LASTPIN (-6275 4825) $PN 36
J 0
(-6265 4835);
DISPLAY 0.680851 (-6265 4835);
PAINT MONO (-6265 4835);
FORCEPROP 0 LASTPIN (-6275 3175) $PN 129
J 0
(-6265 3185);
DISPLAY 0.680851 (-6265 3185);
PAINT MONO (-6265 3185);
FORCEPROP 0 LASTPIN (-6275 4875) $PN 38
J 0
(-6265 4885);
DISPLAY 0.680851 (-6265 4885);
PAINT MONO (-6265 4885);
FORCEPROP 0 LASTPIN (-6275 3225) $PN 131
J 0
(-6265 3235);
DISPLAY 0.680851 (-6265 3235);
PAINT MONO (-6265 3235);
FORCEPROP 0 LASTPIN (-6275 4925) $PN 181
J 0
(-6265 4935);
DISPLAY 0.680851 (-6265 4935);
PAINT MONO (-6265 4935);
FORCEPROP 0 LASTPIN (-6275 3275) $PN 274
J 0
(-6265 3285);
DISPLAY 0.680851 (-6265 3285);
PAINT MONO (-6265 3285);
FORCEPROP 0 LASTPIN (-6275 4975) $PN 183
J 0
(-6265 4985);
DISPLAY 0.680851 (-6265 4985);
PAINT MONO (-6265 4985);
FORCEPROP 0 LASTPIN (-6275 3325) $PN 276
J 0
(-6265 3335);
DISPLAY 0.680851 (-6265 3335);
PAINT MONO (-6265 3335);
FORCEPROP 0 LASTPIN (-6275 5025) $PN 40
J 0
(-6265 5035);
DISPLAY 0.680851 (-6265 5035);
PAINT MONO (-6265 5035);
FORCEPROP 0 LASTPIN (-6275 3375) $PN 133
J 0
(-6265 3385);
DISPLAY 0.680851 (-6265 3385);
PAINT MONO (-6265 3385);
FORCEPROP 0 LASTPIN (-6275 5075) $PN 42
J 0
(-6265 5085);
DISPLAY 0.680851 (-6265 5085);
PAINT MONO (-6265 5085);
FORCEPROP 0 LASTPIN (-6275 3425) $PN 135
J 0
(-6265 3435);
DISPLAY 0.680851 (-6265 3435);
PAINT MONO (-6265 3435);
FORCEPROP 0 LASTPIN (-6275 5125) $PN 185
J 0
(-6265 5135);
DISPLAY 0.680851 (-6265 5135);
PAINT MONO (-6265 5135);
FORCEPROP 0 LASTPIN (-6275 3475) $PN 278
J 0
(-6265 3485);
DISPLAY 0.680851 (-6265 3485);
PAINT MONO (-6265 3485);
FORCEPROP 0 LASTPIN (-6275 5175) $PN 187
J 0
(-6265 5185);
DISPLAY 0.680851 (-6265 5185);
PAINT MONO (-6265 5185);
FORCEPROP 0 LASTPIN (-6275 3525) $PN 280
J 0
(-6265 3535);
DISPLAY 0.680851 (-6265 3535);
PAINT MONO (-6265 3535);
FORCEPROP 0 LASTPIN (-6275 5225) $PN 47
J 0
(-6265 5235);
DISPLAY 0.680851 (-6265 5235);
PAINT MONO (-6265 5235);
FORCEPROP 0 LASTPIN (-6275 3575) $PN 140
J 0
(-6265 3585);
DISPLAY 0.680851 (-6265 3585);
PAINT MONO (-6265 3585);
FORCEPROP 0 LASTPIN (-6275 5275) $PN 49
J 0
(-6265 5285);
DISPLAY 0.680851 (-6265 5285);
PAINT MONO (-6265 5285);
FORCEPROP 0 LASTPIN (-6275 3625) $PN 142
J 0
(-6265 3635);
DISPLAY 0.680851 (-6265 3635);
PAINT MONO (-6265 3635);
FORCEPROP 0 LASTPIN (-6275 5325) $PN 192
J 0
(-6265 5335);
DISPLAY 0.680851 (-6265 5335);
PAINT MONO (-6265 5335);
FORCEPROP 0 LASTPIN (-6275 3675) $PN 285
J 0
(-6265 3685);
DISPLAY 0.680851 (-6265 3685);
PAINT MONO (-6265 3685);
FORCEPROP 0 LASTPIN (-6275 5375) $PN 194
J 0
(-6265 5385);
DISPLAY 0.680851 (-6265 5385);
PAINT MONO (-6265 5385);
FORCEPROP 0 LASTPIN (-6275 3725) $PN 287
J 0
(-6265 3735);
DISPLAY 0.680851 (-6265 3735);
PAINT MONO (-6265 3735);
FORCEPROP 0 LASTPIN (-7475 2875) $PN 148
J 2
(-7485 2885);
DISPLAY 0.680851 (-7485 2885);
PAINT MONO (-7485 2885);
FORCEPROP 0 LASTPIN (-7475 2775) $PN 4
J 2
(-7485 2785);
DISPLAY 0.680851 (-7485 2785);
PAINT MONO (-7485 2785);
FORCEPROP 0 LASTPIN (-7475 2825) $PN 5
J 2
(-7485 2835);
DISPLAY 0.680851 (-7485 2835);
PAINT MONO (-7485 2835);
FORCEPROP 0 LASTPIN (-7475 1975) $PN 86
J 2
(-7485 1985);
DISPLAY 0.680851 (-7485 1985);
PAINT MONO (-7485 1985);
FORCEPROP 0 LASTPIN (-7475 1925) $PN 87
J 2
(-7485 1935);
DISPLAY 0.680851 (-7485 1935);
PAINT MONO (-7485 1935);
FORCEPROP 0 LASTPIN (-7475 4575) $PN 74
J 2
(-7485 4585);
DISPLAY 0.680851 (-7485 4585);
PAINT MONO (-7485 4585);
FORCEPROP 0 LASTPIN (-7475 4525) $PN 227
J 2
(-7485 4535);
DISPLAY 0.680851 (-7485 4535);
PAINT MONO (-7485 4535);
FORCEPROP 0 LASTPIN (-7475 2525) $PN 147
J 2
(-7485 2535);
DISPLAY 0.680851 (-7485 2535);
PAINT MONO (-7485 2535);
FORCEPROP 0 LASTPIN (-7475 3075) $PN 207
J 2
(-7485 3085);
DISPLAY 0.680851 (-7485 3085);
PAINT MONO (-7485 3085);
FORCEPROP 0 LASTPIN (-7475 2125) $PN 2
J 2
(-7485 2135);
DISPLAY 0.680851 (-7485 2135);
PAINT MONO (-7485 2135);
FORCEPROP 0 LASTPIN (-7475 2175) $PN 144
J 2
(-7485 2185);
DISPLAY 0.680851 (-7485 2185);
PAINT MONO (-7485 2185);
FORCEPROP 0 LASTPIN (-7475 2225) $PN 149
J 2
(-7485 2235);
DISPLAY 0.680851 (-7485 2235);
PAINT MONO (-7485 2235);
FORCEPROP 0 LASTPIN (-7475 2275) $PN 150
J 2
(-7485 2285);
DISPLAY 0.680851 (-7485 2285);
PAINT MONO (-7485 2285);
FORCEPROP 0 LASTPIN (-7475 2325) $PN 220
J 2
(-7485 2335);
DISPLAY 0.680851 (-7485 2335);
PAINT MONO (-7485 2335);
FORCEPROP 0 LASTPIN (-7475 2375) $PN 231
J 2
(-7485 2385);
DISPLAY 0.680851 (-7485 2385);
PAINT MONO (-7485 2385);
FORCEPROP 0 LASTPIN (-7475 2425) $PN 232
J 2
(-7485 2435);
DISPLAY 0.680851 (-7485 2435);
PAINT MONO (-7485 2435);
FORCEPROP 0 LASTPIN (-7475 2925) $PN 3
J 2
(-7485 2935);
DISPLAY 0.680851 (-7485 2935);
PAINT MONO (-7485 2935);
FORCEPROP 2 LAST PART_TYPE SMLF
J 0
(-7325 5800);
DISPLAY 1.021277 (-7325 5800);
FORCEPROP 2 LAST VALUE SCONN288_DDR506112002KQ
J 0
(-7325 5750);
DISPLAY 0.489362 (-7325 5750);
PAINT SKYBLUE (-7325 5750);
FORCEPROP 1 LAST MATERIAL IO
J 0
(-7325 5550);
DISPLAY 0.468085 (-7325 5550);
PAINT SKYBLUE (-7325 5550);
FORCEPROP 1 LAST PART_NUMBER DFHST8FS479
J 0
(-7325 5625);
DISPLAY 0.468085 (-7325 5625);
PAINT SKYBLUE (-7325 5625);
FORCEPROP 1 LAST CDS_LMAN_SYM_OUTLINE -450,1900,450,-1850
J 0
(-6875 3625);
DISPLAY 0.468085 (-6875 3625);
PAINT GREEN (-6875 3625);
DISPLAY INVISIBLE (-6875 3625);
FORCEPROP 1 LAST PATH I22
J 0
(-6875 3625);
DISPLAY 0.723404 (-6875 3625);
PAINT GREEN (-6875 3625);
DISPLAY INVISIBLE (-6875 3625);
FORCEPROP 1 LAST NEEDS_NO_SIZE TRUE
J 0
(-6875 3625);
DISPLAY 0.723404 (-6875 3625);
PAINT GREEN (-6875 3625);
DISPLAY INVISIBLE (-6875 3625);
FORCEPROP 2 LAST CDS_LIB pure_quanta
J 0
(-6875 3625);
DISPLAY INVISIBLE (-6875 3625);
FORCEADD TAP..1
(-3475 3700);
FORCEPROP 3 LASTPIN (-3525 3700) SIG_NAME M_K_CPU0_SA_DQS_DP<0>
J 0
(-3515 3710);
DISPLAY 0.659574 (-3515 3710);
PAINT MONO (-3515 3710);
DISPLAY INVISIBLE (-3515 3710);
FORCEPROP 1 LASTPIN (-3525 3700) BN 0
J 0
(-3537 3708);
DISPLAY 0.489362 (-3537 3708);
PAINT GREEN (-3537 3708);
FORCEPROP 2 LAST CDS_LIB mstr_standard
J 0
(-3475 3700);
DISPLAY 0.723404 (-3475 3700);
PAINT MONO (-3475 3700);
DISPLAY INVISIBLE (-3475 3700);
FORCEPROP 1 LAST BODY_TYPE PLUMBING
J 0
(-3475 3750);
DISPLAY 0.872340 (-3475 3750);
PAINT GREEN (-3475 3750);
DISPLAY INVISIBLE (-3475 3750);
FORCEPROP 1 LAST HDL_TAP TRUE
J 0
(-3150 3575);
DISPLAY 0.872340 (-3150 3575);
DISPLAY INVISIBLE (-3150 3575);
FORCEPROP 1 LAST PATH I220
J 0
(-3477 3700);
DISPLAY 0.872340 (-3477 3700);
PAINT GREEN (-3477 3700);
DISPLAY INVISIBLE (-3477 3700);
FORCEADD TAP..1
(-3475 3550);
FORCEPROP 3 LASTPIN (-3525 3550) SIG_NAME M_K_CPU0_SB_DQS_DP<9>
J 0
(-3515 3560);
DISPLAY 0.659574 (-3515 3560);
PAINT MONO (-3515 3560);
DISPLAY INVISIBLE (-3515 3560);
FORCEPROP 1 LASTPIN (-3525 3550) BN 9
J 0
(-3537 3558);
DISPLAY 0.489362 (-3537 3558);
PAINT GREEN (-3537 3558);
FORCEPROP 2 LAST CDS_LIB mstr_standard
J 0
(-3475 3550);
DISPLAY 0.723404 (-3475 3550);
PAINT MONO (-3475 3550);
DISPLAY INVISIBLE (-3475 3550);
FORCEPROP 1 LAST BODY_TYPE PLUMBING
J 0
(-3475 3600);
DISPLAY 0.872340 (-3475 3600);
PAINT GREEN (-3475 3600);
DISPLAY INVISIBLE (-3475 3600);
FORCEPROP 1 LAST HDL_TAP TRUE
J 0
(-3150 3425);
DISPLAY 0.872340 (-3150 3425);
DISPLAY INVISIBLE (-3150 3425);
FORCEPROP 1 LAST PATH I221
J 0
(-3477 3550);
DISPLAY 0.872340 (-3477 3550);
PAINT GREEN (-3477 3550);
DISPLAY INVISIBLE (-3477 3550);
FORCEADD TAP..1
(-3475 3450);
FORCEPROP 3 LASTPIN (-3525 3450) SIG_NAME M_K_CPU0_SB_DQS_DP<8>
J 0
(-3515 3460);
DISPLAY 0.659574 (-3515 3460);
PAINT MONO (-3515 3460);
DISPLAY INVISIBLE (-3515 3460);
FORCEPROP 1 LASTPIN (-3525 3450) BN 8
J 0
(-3537 3458);
DISPLAY 0.489362 (-3537 3458);
PAINT GREEN (-3537 3458);
FORCEPROP 2 LAST CDS_LIB mstr_standard
J 0
(-3475 3450);
DISPLAY 0.723404 (-3475 3450);
PAINT MONO (-3475 3450);
DISPLAY INVISIBLE (-3475 3450);
FORCEPROP 1 LAST BODY_TYPE PLUMBING
J 0
(-3475 3500);
DISPLAY 0.872340 (-3475 3500);
PAINT GREEN (-3475 3500);
DISPLAY INVISIBLE (-3475 3500);
FORCEPROP 1 LAST HDL_TAP TRUE
J 0
(-3150 3325);
DISPLAY 0.872340 (-3150 3325);
DISPLAY INVISIBLE (-3150 3325);
FORCEPROP 1 LAST PATH I222
J 0
(-3477 3450);
DISPLAY 0.872340 (-3477 3450);
PAINT GREEN (-3477 3450);
DISPLAY INVISIBLE (-3477 3450);
FORCEADD TAP..1
(-3275 3300);
FORCEPROP 3 LASTPIN (-3325 3300) SIG_NAME M_K_CPU0_SB_DQS_DN<7>
J 0
(-3315 3310);
DISPLAY 0.659574 (-3315 3310);
PAINT MONO (-3315 3310);
DISPLAY INVISIBLE (-3315 3310);
FORCEPROP 1 LASTPIN (-3325 3300) BN 7
J 0
(-3337 3308);
DISPLAY 0.489362 (-3337 3308);
PAINT GREEN (-3337 3308);
FORCEPROP 2 LAST CDS_LIB mstr_standard
J 0
(-3275 3300);
DISPLAY 0.723404 (-3275 3300);
PAINT MONO (-3275 3300);
DISPLAY INVISIBLE (-3275 3300);
FORCEPROP 1 LAST BODY_TYPE PLUMBING
J 0
(-3275 3350);
DISPLAY 0.872340 (-3275 3350);
PAINT GREEN (-3275 3350);
DISPLAY INVISIBLE (-3275 3350);
FORCEPROP 1 LAST HDL_TAP TRUE
J 0
(-2950 3175);
DISPLAY 0.872340 (-2950 3175);
DISPLAY INVISIBLE (-2950 3175);
FORCEPROP 1 LAST PATH I223
J 0
(-3277 3300);
DISPLAY 0.872340 (-3277 3300);
PAINT GREEN (-3277 3300);
DISPLAY INVISIBLE (-3277 3300);
FORCEADD TAP..1
(-3275 3000);
FORCEPROP 3 LASTPIN (-3325 3000) SIG_NAME M_K_CPU0_SB_DQS_DN<4>
J 0
(-3315 3010);
DISPLAY 0.659574 (-3315 3010);
PAINT MONO (-3315 3010);
DISPLAY INVISIBLE (-3315 3010);
FORCEPROP 1 LASTPIN (-3325 3000) BN 4
J 0
(-3337 3008);
DISPLAY 0.489362 (-3337 3008);
PAINT GREEN (-3337 3008);
FORCEPROP 2 LAST CDS_LIB mstr_standard
J 0
(-3275 3000);
DISPLAY 0.723404 (-3275 3000);
PAINT MONO (-3275 3000);
DISPLAY INVISIBLE (-3275 3000);
FORCEPROP 1 LAST BODY_TYPE PLUMBING
J 0
(-3275 3050);
DISPLAY 0.872340 (-3275 3050);
PAINT GREEN (-3275 3050);
DISPLAY INVISIBLE (-3275 3050);
FORCEPROP 1 LAST HDL_TAP TRUE
J 0
(-2950 2875);
DISPLAY 0.872340 (-2950 2875);
DISPLAY INVISIBLE (-2950 2875);
FORCEPROP 1 LAST PATH I224
J 0
(-3277 3000);
DISPLAY 0.872340 (-3277 3000);
PAINT GREEN (-3277 3000);
DISPLAY INVISIBLE (-3277 3000);
FORCEADD TAP..1
(-3275 3100);
FORCEPROP 3 LASTPIN (-3325 3100) SIG_NAME M_K_CPU0_SB_DQS_DN<5>
J 0
(-3315 3110);
DISPLAY 0.659574 (-3315 3110);
PAINT MONO (-3315 3110);
DISPLAY INVISIBLE (-3315 3110);
FORCEPROP 1 LASTPIN (-3325 3100) BN 5
J 0
(-3337 3108);
DISPLAY 0.489362 (-3337 3108);
PAINT GREEN (-3337 3108);
FORCEPROP 2 LAST CDS_LIB mstr_standard
J 0
(-3275 3100);
DISPLAY 0.723404 (-3275 3100);
PAINT MONO (-3275 3100);
DISPLAY INVISIBLE (-3275 3100);
FORCEPROP 1 LAST BODY_TYPE PLUMBING
J 0
(-3275 3150);
DISPLAY 0.872340 (-3275 3150);
PAINT GREEN (-3275 3150);
DISPLAY INVISIBLE (-3275 3150);
FORCEPROP 1 LAST HDL_TAP TRUE
J 0
(-2950 2975);
DISPLAY 0.872340 (-2950 2975);
DISPLAY INVISIBLE (-2950 2975);
FORCEPROP 1 LAST PATH I225
J 0
(-3277 3100);
DISPLAY 0.872340 (-3277 3100);
PAINT GREEN (-3277 3100);
DISPLAY INVISIBLE (-3277 3100);
FORCEADD TAP..1
(-3275 2900);
FORCEPROP 3 LASTPIN (-3325 2900) SIG_NAME M_K_CPU0_SB_DQS_DN<3>
J 0
(-3315 2910);
DISPLAY 0.659574 (-3315 2910);
PAINT MONO (-3315 2910);
DISPLAY INVISIBLE (-3315 2910);
FORCEPROP 1 LASTPIN (-3325 2900) BN 3
J 0
(-3337 2908);
DISPLAY 0.489362 (-3337 2908);
PAINT GREEN (-3337 2908);
FORCEPROP 2 LAST CDS_LIB mstr_standard
J 0
(-3275 2900);
DISPLAY 0.723404 (-3275 2900);
PAINT MONO (-3275 2900);
DISPLAY INVISIBLE (-3275 2900);
FORCEPROP 1 LAST BODY_TYPE PLUMBING
J 0
(-3275 2950);
DISPLAY 0.872340 (-3275 2950);
PAINT GREEN (-3275 2950);
DISPLAY INVISIBLE (-3275 2950);
FORCEPROP 1 LAST HDL_TAP TRUE
J 0
(-2950 2775);
DISPLAY 0.872340 (-2950 2775);
DISPLAY INVISIBLE (-2950 2775);
FORCEPROP 1 LAST PATH I226
J 0
(-3277 2900);
DISPLAY 0.872340 (-3277 2900);
PAINT GREEN (-3277 2900);
DISPLAY INVISIBLE (-3277 2900);
FORCEADD TAP..1
(-3275 2800);
FORCEPROP 3 LASTPIN (-3325 2800) SIG_NAME M_K_CPU0_SB_DQS_DN<2>
J 0
(-3315 2810);
DISPLAY 0.659574 (-3315 2810);
PAINT MONO (-3315 2810);
DISPLAY INVISIBLE (-3315 2810);
FORCEPROP 1 LASTPIN (-3325 2800) BN 2
J 0
(-3337 2808);
DISPLAY 0.489362 (-3337 2808);
PAINT GREEN (-3337 2808);
FORCEPROP 2 LAST CDS_LIB mstr_standard
J 0
(-3275 2800);
DISPLAY 0.723404 (-3275 2800);
PAINT MONO (-3275 2800);
DISPLAY INVISIBLE (-3275 2800);
FORCEPROP 1 LAST BODY_TYPE PLUMBING
J 0
(-3275 2850);
DISPLAY 0.872340 (-3275 2850);
PAINT GREEN (-3275 2850);
DISPLAY INVISIBLE (-3275 2850);
FORCEPROP 1 LAST HDL_TAP TRUE
J 0
(-2950 2675);
DISPLAY 0.872340 (-2950 2675);
DISPLAY INVISIBLE (-2950 2675);
FORCEPROP 1 LAST PATH I227
J 0
(-3277 2800);
DISPLAY 0.872340 (-3277 2800);
PAINT GREEN (-3277 2800);
DISPLAY INVISIBLE (-3277 2800);
FORCEADD TAP..1
(-3275 2700);
FORCEPROP 3 LASTPIN (-3325 2700) SIG_NAME M_K_CPU0_SB_DQS_DN<1>
J 0
(-3315 2710);
DISPLAY 0.659574 (-3315 2710);
PAINT MONO (-3315 2710);
DISPLAY INVISIBLE (-3315 2710);
FORCEPROP 1 LASTPIN (-3325 2700) BN 1
J 0
(-3337 2708);
DISPLAY 0.489362 (-3337 2708);
PAINT GREEN (-3337 2708);
FORCEPROP 2 LAST CDS_LIB mstr_standard
J 0
(-3275 2700);
DISPLAY 0.723404 (-3275 2700);
PAINT MONO (-3275 2700);
DISPLAY INVISIBLE (-3275 2700);
FORCEPROP 1 LAST BODY_TYPE PLUMBING
J 0
(-3275 2750);
DISPLAY 0.872340 (-3275 2750);
PAINT GREEN (-3275 2750);
DISPLAY INVISIBLE (-3275 2750);
FORCEPROP 1 LAST HDL_TAP TRUE
J 0
(-2950 2575);
DISPLAY 0.872340 (-2950 2575);
DISPLAY INVISIBLE (-2950 2575);
FORCEPROP 1 LAST PATH I228
J 0
(-3277 2700);
DISPLAY 0.872340 (-3277 2700);
PAINT GREEN (-3277 2700);
DISPLAY INVISIBLE (-3277 2700);
FORCEADD TAP..1
(-3275 2600);
FORCEPROP 3 LASTPIN (-3325 2600) SIG_NAME M_K_CPU0_SB_DQS_DN<0>
J 0
(-3315 2610);
DISPLAY 0.659574 (-3315 2610);
PAINT MONO (-3315 2610);
DISPLAY INVISIBLE (-3315 2610);
FORCEPROP 1 LASTPIN (-3325 2600) BN 0
J 0
(-3337 2608);
DISPLAY 0.489362 (-3337 2608);
PAINT GREEN (-3337 2608);
FORCEPROP 2 LAST CDS_LIB mstr_standard
J 0
(-3275 2600);
DISPLAY 0.723404 (-3275 2600);
PAINT MONO (-3275 2600);
DISPLAY INVISIBLE (-3275 2600);
FORCEPROP 1 LAST BODY_TYPE PLUMBING
J 0
(-3275 2650);
DISPLAY 0.872340 (-3275 2650);
PAINT GREEN (-3275 2650);
DISPLAY INVISIBLE (-3275 2650);
FORCEPROP 1 LAST HDL_TAP TRUE
J 0
(-2950 2475);
DISPLAY 0.872340 (-2950 2475);
DISPLAY INVISIBLE (-2950 2475);
FORCEPROP 1 LAST PATH I229
J 0
(-3277 2600);
DISPLAY 0.872340 (-3277 2600);
PAINT GREEN (-3277 2600);
DISPLAY INVISIBLE (-3277 2600);
FORCEADD TAP..1
R 2
(-7725 3175);
FORCEPROP 3 LASTPIN (-7675 3175) SIG_NAME M_K_CPU0_SB_CB<0>
J 0
(-7665 3185);
DISPLAY 0.659574 (-7665 3185);
PAINT MONO (-7665 3185);
DISPLAY INVISIBLE (-7665 3185);
FORCEPROP 1 LASTPIN (-7675 3175) BN 0
J 2
(-7663 3183);
DISPLAY 0.489362 (-7663 3183);
PAINT GREEN (-7663 3183);
FORCEPROP 2 LAST CDS_LIB mstr_standard
J 0
(-7725 3175);
DISPLAY 0.723404 (-7725 3175);
PAINT MONO (-7725 3175);
DISPLAY INVISIBLE (-7725 3175);
FORCEPROP 1 LAST BODY_TYPE PLUMBING
J 2
(-7725 3225);
DISPLAY 0.872340 (-7725 3225);
PAINT GREEN (-7725 3225);
DISPLAY INVISIBLE (-7725 3225);
FORCEPROP 1 LAST HDL_TAP TRUE
J 2
(-8050 3050);
DISPLAY 0.872340 (-8050 3050);
DISPLAY INVISIBLE (-8050 3050);
FORCEPROP 1 LAST PATH I23
J 2
(-7723 3175);
DISPLAY 0.872340 (-7723 3175);
PAINT GREEN (-7723 3175);
DISPLAY INVISIBLE (-7723 3175);
FORCEADD TAP..1
(-3475 3150);
FORCEPROP 3 LASTPIN (-3525 3150) SIG_NAME M_K_CPU0_SB_DQS_DP<5>
J 0
(-3515 3160);
DISPLAY 0.659574 (-3515 3160);
PAINT MONO (-3515 3160);
DISPLAY INVISIBLE (-3515 3160);
FORCEPROP 1 LASTPIN (-3525 3150) BN 5
J 0
(-3537 3158);
DISPLAY 0.489362 (-3537 3158);
PAINT GREEN (-3537 3158);
FORCEPROP 2 LAST CDS_LIB mstr_standard
J 0
(-3475 3150);
DISPLAY 0.723404 (-3475 3150);
PAINT MONO (-3475 3150);
DISPLAY INVISIBLE (-3475 3150);
FORCEPROP 1 LAST BODY_TYPE PLUMBING
J 0
(-3475 3200);
DISPLAY 0.872340 (-3475 3200);
PAINT GREEN (-3475 3200);
DISPLAY INVISIBLE (-3475 3200);
FORCEPROP 1 LAST HDL_TAP TRUE
J 0
(-3150 3025);
DISPLAY 0.872340 (-3150 3025);
DISPLAY INVISIBLE (-3150 3025);
FORCEPROP 1 LAST PATH I230
J 0
(-3477 3150);
DISPLAY 0.872340 (-3477 3150);
PAINT GREEN (-3477 3150);
DISPLAY INVISIBLE (-3477 3150);
FORCEADD TAP..1
(-3475 3050);
FORCEPROP 3 LASTPIN (-3525 3050) SIG_NAME M_K_CPU0_SB_DQS_DP<4>
J 0
(-3515 3060);
DISPLAY 0.659574 (-3515 3060);
PAINT MONO (-3515 3060);
DISPLAY INVISIBLE (-3515 3060);
FORCEPROP 1 LASTPIN (-3525 3050) BN 4
J 0
(-3537 3058);
DISPLAY 0.489362 (-3537 3058);
PAINT GREEN (-3537 3058);
FORCEPROP 2 LAST CDS_LIB mstr_standard
J 0
(-3475 3050);
DISPLAY 0.723404 (-3475 3050);
PAINT MONO (-3475 3050);
DISPLAY INVISIBLE (-3475 3050);
FORCEPROP 1 LAST BODY_TYPE PLUMBING
J 0
(-3475 3100);
DISPLAY 0.872340 (-3475 3100);
PAINT GREEN (-3475 3100);
DISPLAY INVISIBLE (-3475 3100);
FORCEPROP 1 LAST HDL_TAP TRUE
J 0
(-3150 2925);
DISPLAY 0.872340 (-3150 2925);
DISPLAY INVISIBLE (-3150 2925);
FORCEPROP 1 LAST PATH I231
J 0
(-3477 3050);
DISPLAY 0.872340 (-3477 3050);
PAINT GREEN (-3477 3050);
DISPLAY INVISIBLE (-3477 3050);
FORCEADD TAP..1
(-3475 2950);
FORCEPROP 3 LASTPIN (-3525 2950) SIG_NAME M_K_CPU0_SB_DQS_DP<3>
J 0
(-3515 2960);
DISPLAY 0.659574 (-3515 2960);
PAINT MONO (-3515 2960);
DISPLAY INVISIBLE (-3515 2960);
FORCEPROP 1 LASTPIN (-3525 2950) BN 3
J 0
(-3537 2958);
DISPLAY 0.489362 (-3537 2958);
PAINT GREEN (-3537 2958);
FORCEPROP 2 LAST CDS_LIB mstr_standard
J 0
(-3475 2950);
DISPLAY 0.723404 (-3475 2950);
PAINT MONO (-3475 2950);
DISPLAY INVISIBLE (-3475 2950);
FORCEPROP 1 LAST BODY_TYPE PLUMBING
J 0
(-3475 3000);
DISPLAY 0.872340 (-3475 3000);
PAINT GREEN (-3475 3000);
DISPLAY INVISIBLE (-3475 3000);
FORCEPROP 1 LAST HDL_TAP TRUE
J 0
(-3150 2825);
DISPLAY 0.872340 (-3150 2825);
DISPLAY INVISIBLE (-3150 2825);
FORCEPROP 1 LAST PATH I232
J 0
(-3477 2950);
DISPLAY 0.872340 (-3477 2950);
PAINT GREEN (-3477 2950);
DISPLAY INVISIBLE (-3477 2950);
FORCEADD TAP..1
(-3475 2850);
FORCEPROP 3 LASTPIN (-3525 2850) SIG_NAME M_K_CPU0_SB_DQS_DP<2>
J 0
(-3515 2860);
DISPLAY 0.659574 (-3515 2860);
PAINT MONO (-3515 2860);
DISPLAY INVISIBLE (-3515 2860);
FORCEPROP 1 LASTPIN (-3525 2850) BN 2
J 0
(-3537 2858);
DISPLAY 0.489362 (-3537 2858);
PAINT GREEN (-3537 2858);
FORCEPROP 2 LAST CDS_LIB mstr_standard
J 0
(-3475 2850);
DISPLAY 0.723404 (-3475 2850);
PAINT MONO (-3475 2850);
DISPLAY INVISIBLE (-3475 2850);
FORCEPROP 1 LAST BODY_TYPE PLUMBING
J 0
(-3475 2900);
DISPLAY 0.872340 (-3475 2900);
PAINT GREEN (-3475 2900);
DISPLAY INVISIBLE (-3475 2900);
FORCEPROP 1 LAST HDL_TAP TRUE
J 0
(-3150 2725);
DISPLAY 0.872340 (-3150 2725);
DISPLAY INVISIBLE (-3150 2725);
FORCEPROP 1 LAST PATH I233
J 0
(-3477 2850);
DISPLAY 0.872340 (-3477 2850);
PAINT GREEN (-3477 2850);
DISPLAY INVISIBLE (-3477 2850);
FORCEADD TAP..1
(-3475 2750);
FORCEPROP 3 LASTPIN (-3525 2750) SIG_NAME M_K_CPU0_SB_DQS_DP<1>
J 0
(-3515 2760);
DISPLAY 0.659574 (-3515 2760);
PAINT MONO (-3515 2760);
DISPLAY INVISIBLE (-3515 2760);
FORCEPROP 1 LASTPIN (-3525 2750) BN 1
J 0
(-3537 2758);
DISPLAY 0.489362 (-3537 2758);
PAINT GREEN (-3537 2758);
FORCEPROP 2 LAST CDS_LIB mstr_standard
J 0
(-3475 2750);
DISPLAY 0.723404 (-3475 2750);
PAINT MONO (-3475 2750);
DISPLAY INVISIBLE (-3475 2750);
FORCEPROP 1 LAST BODY_TYPE PLUMBING
J 0
(-3475 2800);
DISPLAY 0.872340 (-3475 2800);
PAINT GREEN (-3475 2800);
DISPLAY INVISIBLE (-3475 2800);
FORCEPROP 1 LAST HDL_TAP TRUE
J 0
(-3150 2625);
DISPLAY 0.872340 (-3150 2625);
DISPLAY INVISIBLE (-3150 2625);
FORCEPROP 1 LAST PATH I234
J 0
(-3477 2750);
DISPLAY 0.872340 (-3477 2750);
PAINT GREEN (-3477 2750);
DISPLAY INVISIBLE (-3477 2750);
FORCEADD TAP..1
(-3475 2650);
FORCEPROP 3 LASTPIN (-3525 2650) SIG_NAME M_K_CPU0_SB_DQS_DP<0>
J 0
(-3515 2660);
DISPLAY 0.659574 (-3515 2660);
PAINT MONO (-3515 2660);
DISPLAY INVISIBLE (-3515 2660);
FORCEPROP 1 LASTPIN (-3525 2650) BN 0
J 0
(-3537 2658);
DISPLAY 0.489362 (-3537 2658);
PAINT GREEN (-3537 2658);
FORCEPROP 2 LAST CDS_LIB mstr_standard
J 0
(-3475 2650);
DISPLAY 0.723404 (-3475 2650);
PAINT MONO (-3475 2650);
DISPLAY INVISIBLE (-3475 2650);
FORCEPROP 1 LAST BODY_TYPE PLUMBING
J 0
(-3475 2700);
DISPLAY 0.872340 (-3475 2700);
PAINT GREEN (-3475 2700);
DISPLAY INVISIBLE (-3475 2700);
FORCEPROP 1 LAST HDL_TAP TRUE
J 0
(-3150 2525);
DISPLAY 0.872340 (-3150 2525);
DISPLAY INVISIBLE (-3150 2525);
FORCEPROP 1 LAST PATH I235
J 0
(-3477 2650);
DISPLAY 0.872340 (-3477 2650);
PAINT GREEN (-3477 2650);
DISPLAY INVISIBLE (-3477 2650);
FORCEADD SCONN288_DDR506112002KQ..2
(-4425 3600);
FORCEPROP 1 LAST LOCATION J20
J 0
(-5025 4925);
DISPLAY 0.468085 (-5025 4925);
PAINT SKYBLUE (-5025 4925);
FORCEPROP 0 LAST $SEC 2
J 0
(-4875 5075);
DISPLAY 0.680851 (-4875 5075);
PAINT MONO (-4875 5075);
DISPLAY INVISIBLE (-4875 5075);
FORCEPROP 0 LAST CDS_SEC 2
J 0
(-4875 5075);
DISPLAY 1.021277 (-4875 5075);
DISPLAY INVISIBLE (-4875 5075);
FORCEPROP 0 LASTPIN (-3675 3650) $PN 12
J 0
(-3665 3660);
DISPLAY 0.680851 (-3665 3660);
PAINT MONO (-3665 3660);
FORCEPROP 0 LASTPIN (-3675 3700) $PN 11
J 0
(-3665 3710);
DISPLAY 0.680851 (-3665 3710);
PAINT MONO (-3665 3710);
FORCEPROP 0 LASTPIN (-3675 2600) $PN 105
J 0
(-3665 2610);
DISPLAY 0.680851 (-3665 2610);
PAINT MONO (-3665 2610);
FORCEPROP 0 LASTPIN (-3675 2650) $PN 104
J 0
(-3665 2660);
DISPLAY 0.680851 (-3665 2660);
PAINT MONO (-3665 2660);
FORCEPROP 0 LASTPIN (-3675 3750) $PN 23
J 0
(-3665 3760);
DISPLAY 0.680851 (-3665 3760);
PAINT MONO (-3665 3760);
FORCEPROP 0 LASTPIN (-3675 3800) $PN 22
J 0
(-3665 3810);
DISPLAY 0.680851 (-3665 3810);
PAINT MONO (-3665 3810);
FORCEPROP 0 LASTPIN (-3675 2700) $PN 116
J 0
(-3665 2710);
DISPLAY 0.680851 (-3665 2710);
PAINT MONO (-3665 2710);
FORCEPROP 0 LASTPIN (-3675 2750) $PN 115
J 0
(-3665 2760);
DISPLAY 0.680851 (-3665 2760);
PAINT MONO (-3665 2760);
FORCEPROP 0 LASTPIN (-3675 3850) $PN 34
J 0
(-3665 3860);
DISPLAY 0.680851 (-3665 3860);
PAINT MONO (-3665 3860);
FORCEPROP 0 LASTPIN (-3675 3900) $PN 33
J 0
(-3665 3910);
DISPLAY 0.680851 (-3665 3910);
PAINT MONO (-3665 3910);
FORCEPROP 0 LASTPIN (-3675 2800) $PN 127
J 0
(-3665 2810);
DISPLAY 0.680851 (-3665 2810);
PAINT MONO (-3665 2810);
FORCEPROP 0 LASTPIN (-3675 2850) $PN 126
J 0
(-3665 2860);
DISPLAY 0.680851 (-3665 2860);
PAINT MONO (-3665 2860);
FORCEPROP 0 LASTPIN (-3675 3950) $PN 45
J 0
(-3665 3960);
DISPLAY 0.680851 (-3665 3960);
PAINT MONO (-3665 3960);
FORCEPROP 0 LASTPIN (-3675 4000) $PN 44
J 0
(-3665 4010);
DISPLAY 0.680851 (-3665 4010);
PAINT MONO (-3665 4010);
FORCEPROP 0 LASTPIN (-3675 2900) $PN 138
J 0
(-3665 2910);
DISPLAY 0.680851 (-3665 2910);
PAINT MONO (-3665 2910);
FORCEPROP 0 LASTPIN (-3675 2950) $PN 137
J 0
(-3665 2960);
DISPLAY 0.680851 (-3665 2960);
PAINT MONO (-3665 2960);
FORCEPROP 0 LASTPIN (-3675 4050) $PN 56
J 0
(-3665 4060);
DISPLAY 0.680851 (-3665 4060);
PAINT MONO (-3665 4060);
FORCEPROP 0 LASTPIN (-3675 4100) $PN 55
J 0
(-3665 4110);
DISPLAY 0.680851 (-3665 4110);
PAINT MONO (-3665 4110);
FORCEPROP 0 LASTPIN (-3675 3000) $PN 238
J 0
(-3665 3010);
DISPLAY 0.680851 (-3665 3010);
PAINT MONO (-3665 3010);
FORCEPROP 0 LASTPIN (-3675 3050) $PN 239
J 0
(-3665 3060);
DISPLAY 0.680851 (-3665 3060);
PAINT MONO (-3665 3060);
FORCEPROP 0 LASTPIN (-3675 4150) $PN 156
J 0
(-3665 4160);
DISPLAY 0.680851 (-3665 4160);
PAINT MONO (-3665 4160);
FORCEPROP 0 LASTPIN (-3675 4200) $PN 157
J 0
(-3665 4210);
DISPLAY 0.680851 (-3665 4210);
PAINT MONO (-3665 4210);
FORCEPROP 0 LASTPIN (-3675 3100) $PN 249
J 0
(-3665 3110);
DISPLAY 0.680851 (-3665 3110);
PAINT MONO (-3665 3110);
FORCEPROP 0 LASTPIN (-3675 3150) $PN 250
J 0
(-3665 3160);
DISPLAY 0.680851 (-3665 3160);
PAINT MONO (-3665 3160);
FORCEPROP 0 LASTPIN (-3675 4250) $PN 167
J 0
(-3665 4260);
DISPLAY 0.680851 (-3665 4260);
PAINT MONO (-3665 4260);
FORCEPROP 0 LASTPIN (-3675 4300) $PN 168
J 0
(-3665 4310);
DISPLAY 0.680851 (-3665 4310);
PAINT MONO (-3665 4310);
FORCEPROP 0 LASTPIN (-3675 3200) $PN 260
J 0
(-3665 3210);
DISPLAY 0.680851 (-3665 3210);
PAINT MONO (-3665 3210);
FORCEPROP 0 LASTPIN (-3675 3250) $PN 261
J 0
(-3665 3260);
DISPLAY 0.680851 (-3665 3260);
PAINT MONO (-3665 3260);
FORCEPROP 0 LASTPIN (-3675 4350) $PN 178
J 0
(-3665 4360);
DISPLAY 0.680851 (-3665 4360);
PAINT MONO (-3665 4360);
FORCEPROP 0 LASTPIN (-3675 4400) $PN 179
J 0
(-3665 4410);
DISPLAY 0.680851 (-3665 4410);
PAINT MONO (-3665 4410);
FORCEPROP 0 LASTPIN (-3675 3300) $PN 271
J 0
(-3665 3310);
DISPLAY 0.680851 (-3665 3310);
PAINT MONO (-3665 3310);
FORCEPROP 0 LASTPIN (-3675 3350) $PN 272
J 0
(-3665 3360);
DISPLAY 0.680851 (-3665 3360);
PAINT MONO (-3665 3360);
FORCEPROP 0 LASTPIN (-3675 4450) $PN 189
J 0
(-3665 4460);
DISPLAY 0.680851 (-3665 4460);
PAINT MONO (-3665 4460);
FORCEPROP 0 LASTPIN (-3675 4500) $PN 190
J 0
(-3665 4510);
DISPLAY 0.680851 (-3665 4510);
PAINT MONO (-3665 4510);
FORCEPROP 0 LASTPIN (-3675 3400) $PN 282
J 0
(-3665 3410);
DISPLAY 0.680851 (-3665 3410);
PAINT MONO (-3665 3410);
FORCEPROP 0 LASTPIN (-3675 3450) $PN 283
J 0
(-3665 3460);
DISPLAY 0.680851 (-3665 3460);
PAINT MONO (-3665 3460);
FORCEPROP 0 LASTPIN (-3675 4550) $PN 200
J 0
(-3665 4560);
DISPLAY 0.680851 (-3665 4560);
PAINT MONO (-3665 4560);
FORCEPROP 0 LASTPIN (-3675 4600) $PN 201
J 0
(-3665 4610);
DISPLAY 0.680851 (-3665 4610);
PAINT MONO (-3665 4610);
FORCEPROP 0 LASTPIN (-3675 3500) $PN 94
J 0
(-3665 3510);
DISPLAY 0.680851 (-3665 3510);
PAINT MONO (-3665 3510);
FORCEPROP 0 LASTPIN (-3675 3550) $PN 93
J 0
(-3665 3560);
DISPLAY 0.680851 (-3665 3560);
PAINT MONO (-3665 3560);
FORCEPROP 2 LAST PART_TYPE SMLF
J 0
(-4875 5025);
DISPLAY 1.021277 (-4875 5025);
FORCEPROP 2 LAST VALUE SCONN288_DDR506112002KQ
J 0
(-4875 4975);
DISPLAY 0.489362 (-4875 4975);
PAINT SKYBLUE (-4875 4975);
FORCEPROP 1 LAST MATERIAL IO
J 0
(-5025 4775);
DISPLAY 0.468085 (-5025 4775);
PAINT SKYBLUE (-5025 4775);
FORCEPROP 1 LAST PART_NUMBER DFHST8FS479
J 0
(-5025 4850);
DISPLAY 0.468085 (-5025 4850);
PAINT SKYBLUE (-5025 4850);
FORCEPROP 1 LAST CDS_LMAN_SYM_OUTLINE -600,1150,600,-1150
J 0
(-4425 3600);
DISPLAY 0.468085 (-4425 3600);
PAINT GREEN (-4425 3600);
DISPLAY INVISIBLE (-4425 3600);
FORCEPROP 1 LAST PATH I236
J 0
(-4425 3600);
DISPLAY 0.723404 (-4425 3600);
PAINT GREEN (-4425 3600);
DISPLAY INVISIBLE (-4425 3600);
FORCEPROP 1 LAST NEEDS_NO_SIZE TRUE
J 0
(-4425 3600);
DISPLAY 0.723404 (-4425 3600);
PAINT GREEN (-4425 3600);
DISPLAY INVISIBLE (-4425 3600);
FORCEPROP 2 LAST CDS_LIB pure_quanta
J 0
(-4425 3600);
DISPLAY INVISIBLE (-4425 3600);
FORCEADD GND..1
(-2825 5650);
FORCEPROP 3 LASTPIN (-2825 5700) SIG_NAME GND\g
J 0
(-2815 5710);
DISPLAY 0.659574 (-2815 5710);
PAINT MONO (-2815 5710);
DISPLAY INVISIBLE (-2815 5710);
FORCEPROP 2 LAST CDS_LIB pure_quanta_power
J 0
(-2825 5650);
DISPLAY INVISIBLE (-2825 5650);
FORCEPROP 2 LAST BOM_COST MEM
J 0
(-2800 5775);
DISPLAY 0.659574 (-2800 5775);
DISPLAY INVISIBLE (-2800 5775);
FORCEPROP 1 LAST SIZE 1B
J 0
(-2750 5600);
DISPLAY 0.723404 (-2750 5600);
PAINT GREEN (-2750 5600);
DISPLAY INVISIBLE (-2750 5600);
FORCEPROP 1 LAST PATH I237
J 0
(-2750 5650);
DISPLAY 0.872340 (-2750 5650);
PAINT AQUA (-2750 5650);
DISPLAY INVISIBLE (-2750 5650);
FORCEPROP 2 LAST ROOM MEM_EFGH_DECOUPLING_CAPS
J 0
(-2800 5725);
DISPLAY 0.659574 (-2800 5725);
PAINT RED (-2800 5725);
DISPLAY INVISIBLE (-2800 5725);
FORCEPROP 1 LAST HDL_POWER GND
J 0
(-2825 5800);
DISPLAY 0.723404 (-2825 5800);
PAINT GREEN (-2825 5800);
DISPLAY INVISIBLE (-2825 5800);
FORCEADD Q_CAP..1
R 2
(-2825 6000);
FORCEPROP 1 LAST LOCATION C167
J 2
(-2875 6100);
DISPLAY 0.489362 (-2875 6100);
PAINT SKYBLUE (-2875 6100);
FORCEPROP 0 LAST $SEC 1
J 0
(-2875 6150);
DISPLAY 0.680851 (-2875 6150);
PAINT MONO (-2875 6150);
DISPLAY INVISIBLE (-2875 6150);
FORCEPROP 0 LAST CDS_SEC 1
J 0
(-2875 6150);
DISPLAY 0.680851 (-2875 6150);
DISPLAY INVISIBLE (-2875 6150);
FORCEPROP 1 LASTPIN (-2825 6100) $PN 1
J 2
(-2835 6080);
DISPLAY 0.489362 (-2835 6080);
PAINT MONO (-2835 6080);
FORCEPROP 1 LASTPIN (-2825 5900) $PN 2
J 2
(-2835 5880);
DISPLAY 0.489362 (-2835 5880);
PAINT MONO (-2835 5880);
FORCEPROP 1 LAST MATERIAL X6S
J 2
(-2875 5900);
DISPLAY 0.489362 (-2875 5900);
PAINT SKYBLUE (-2875 5900);
FORCEPROP 1 LAST TOLERANCE 10%
J 2
(-2875 5950);
DISPLAY 0.489362 (-2875 5950);
PAINT SKYBLUE (-2875 5950);
FORCEPROP 1 LAST VALUE 10UF
J 2
(-2875 6050);
DISPLAY 0.489362 (-2875 6050);
PAINT SKYBLUE (-2875 6050);
FORCEPROP 1 LAST PART_NUMBER CH6104KEA00
J 2
(-2875 5850);
DISPLAY 0.489362 (-2875 5850);
PAINT SKYBLUE (-2875 5850);
FORCEPROP 1 LAST VOLTAGE 25V
J 2
(-2875 6000);
DISPLAY 0.489362 (-2875 6000);
PAINT SKYBLUE (-2875 6000);
FORCEPROP 1 LAST PACK_TYPE C0805
J 2
(-2875 5800);
DISPLAY 0.489362 (-2875 5800);
PAINT SKYBLUE (-2875 5800);
FORCEPROP 0 LAST BOM_COST MEM
J 2
(-2880 6145);
DISPLAY 0.595745 (-2880 6145);
PAINT MONO (-2880 6145);
DISPLAY INVISIBLE (-2880 6145);
FORCEPROP 2 LAST CDS_LIB pure_quanta
J 0
(-2825 6000);
DISPLAY INVISIBLE (-2825 6000);
FORCEPROP 1 LAST PATH I238
J 2
(-2875 6150);
DISPLAY 0.978723 (-2875 6150);
PAINT WHITE (-2875 6150);
DISPLAY INVISIBLE (-2875 6150);
FORCEPROP 0 LAST ROOM MEM_CH_A_CPU0_DIMM1
J 2
(-2880 6145);
DISPLAY 0.595745 (-2880 6145);
PAINT RED (-2880 6145);
DISPLAY INVISIBLE (-2880 6145);
FORCEADD Q_CAP..1
R 2
(-2250 6000);
FORCEPROP 1 LAST LOCATION C169
J 2
(-2300 6100);
DISPLAY 0.489362 (-2300 6100);
PAINT SKYBLUE (-2300 6100);
FORCEPROP 0 LAST $SEC 1
J 0
(-2300 6150);
DISPLAY 0.680851 (-2300 6150);
PAINT MONO (-2300 6150);
DISPLAY INVISIBLE (-2300 6150);
FORCEPROP 0 LAST CDS_SEC 1
J 0
(-2300 6150);
DISPLAY 0.680851 (-2300 6150);
DISPLAY INVISIBLE (-2300 6150);
FORCEPROP 1 LASTPIN (-2250 6100) $PN 1
J 2
(-2260 6080);
DISPLAY 0.489362 (-2260 6080);
PAINT MONO (-2260 6080);
FORCEPROP 1 LASTPIN (-2250 5900) $PN 2
J 2
(-2260 5880);
DISPLAY 0.489362 (-2260 5880);
PAINT MONO (-2260 5880);
FORCEPROP 1 LAST MATERIAL X6S
J 2
(-2300 5900);
DISPLAY 0.489362 (-2300 5900);
PAINT SKYBLUE (-2300 5900);
FORCEPROP 1 LAST TOLERANCE 10%
J 2
(-2300 5950);
DISPLAY 0.489362 (-2300 5950);
PAINT SKYBLUE (-2300 5950);
FORCEPROP 1 LAST VALUE 10UF
J 2
(-2300 6050);
DISPLAY 0.489362 (-2300 6050);
PAINT SKYBLUE (-2300 6050);
FORCEPROP 1 LAST PART_NUMBER CH6104KEA00
J 2
(-2300 5850);
DISPLAY 0.489362 (-2300 5850);
PAINT SKYBLUE (-2300 5850);
FORCEPROP 1 LAST VOLTAGE 25V
J 2
(-2300 6000);
DISPLAY 0.489362 (-2300 6000);
PAINT SKYBLUE (-2300 6000);
FORCEPROP 1 LAST PACK_TYPE C0805
J 2
(-2300 5800);
DISPLAY 0.489362 (-2300 5800);
PAINT SKYBLUE (-2300 5800);
FORCEPROP 0 LAST BOM_COST MEM
J 2
(-2305 6145);
DISPLAY 0.595745 (-2305 6145);
PAINT MONO (-2305 6145);
DISPLAY INVISIBLE (-2305 6145);
FORCEPROP 2 LAST CDS_LIB pure_quanta
J 0
(-2250 6000);
DISPLAY INVISIBLE (-2250 6000);
FORCEPROP 1 LAST PATH I239
J 2
(-2300 6150);
DISPLAY 0.978723 (-2300 6150);
PAINT WHITE (-2300 6150);
DISPLAY INVISIBLE (-2300 6150);
FORCEPROP 0 LAST ROOM MEM_CH_A_CPU0_DIMM1
J 2
(-2305 6145);
DISPLAY 0.595745 (-2305 6145);
PAINT RED (-2305 6145);
DISPLAY INVISIBLE (-2305 6145);
FORCEADD TAP..1
R 2
(-7725 3225);
FORCEPROP 3 LASTPIN (-7675 3225) SIG_NAME M_K_CPU0_SB_CB<1>
J 0
(-7665 3235);
DISPLAY 0.659574 (-7665 3235);
PAINT MONO (-7665 3235);
DISPLAY INVISIBLE (-7665 3235);
FORCEPROP 1 LASTPIN (-7675 3225) BN 1
J 2
(-7663 3233);
DISPLAY 0.489362 (-7663 3233);
PAINT GREEN (-7663 3233);
FORCEPROP 2 LAST CDS_LIB mstr_standard
J 0
(-7725 3225);
DISPLAY 0.723404 (-7725 3225);
PAINT MONO (-7725 3225);
DISPLAY INVISIBLE (-7725 3225);
FORCEPROP 1 LAST BODY_TYPE PLUMBING
J 2
(-7725 3275);
DISPLAY 0.872340 (-7725 3275);
PAINT GREEN (-7725 3275);
DISPLAY INVISIBLE (-7725 3275);
FORCEPROP 1 LAST HDL_TAP TRUE
J 2
(-8050 3100);
DISPLAY 0.872340 (-8050 3100);
DISPLAY INVISIBLE (-8050 3100);
FORCEPROP 1 LAST PATH I24
J 2
(-7723 3225);
DISPLAY 0.872340 (-7723 3225);
PAINT GREEN (-7723 3225);
DISPLAY INVISIBLE (-7723 3225);
FORCEADD UNIVERSAL_POWER..1
(-2825 6325);
FORCEPROP 3 LASTPIN (-2825 6275) SIG_NAME P12V_MEM_0\g
J 0
(-2815 6285);
DISPLAY 0.659574 (-2815 6285);
PAINT MONO (-2815 6285);
DISPLAY INVISIBLE (-2815 6285);
FORCEPROP 1 LAST HDL_POWER P12V_MEM_0
J 1
(-2850 6375);
DISPLAY 0.489362 (-2850 6375);
PAINT GREEN (-2850 6375);
FORCEPROP 2 LAST BOM_COST VR_SYSTEM
J 0
(-2825 6425);
DISPLAY 0.617021 (-2825 6425);
PAINT PURPLE (-2825 6425);
DISPLAY INVISIBLE (-2825 6425);
FORCEPROP 2 LAST CDS_LIB pure_quanta_power
J 0
(-2825 6325);
DISPLAY INVISIBLE (-2825 6325);
FORCEPROP 1 LAST PATH I240
J 0
(-2775 6350);
DISPLAY 0.872340 (-2775 6350);
PAINT AQUA (-2775 6350);
DISPLAY INVISIBLE (-2775 6350);
FORCEADD OFFPAGE..1
(-8350 2675);
FORCEPROP 2 LAST $XR5 96 
J 0
(-9052 2675);
DISPLAY 0.638298 (-9052 2675);
PAINT MONO (-9052 2675);
FORCEPROP 2 LAST $XR4 94 
J 0
(-8962 2675);
DISPLAY 0.638298 (-8962 2675);
PAINT MONO (-8962 2675);
FORCEPROP 2 LAST $XR3 93 
J 0
(-8872 2675);
DISPLAY 0.638298 (-8872 2675);
PAINT MONO (-8872 2675);
FORCEPROP 2 LAST $XR2 92 
J 0
(-8782 2675);
DISPLAY 0.638298 (-8782 2675);
PAINT MONO (-8782 2675);
FORCEPROP 2 LAST $XR1 91 
J 0
(-8692 2675);
DISPLAY 0.638298 (-8692 2675);
PAINT MONO (-8692 2675);
FORCEPROP 2 LAST $XR0 136 
J 0
(-8602 2675);
DISPLAY 0.638298 (-8602 2675);
PAINT MONO (-8602 2675);
FORCEPROP 2 LAST PATH I241
J 0
(-8625 2725);
DISPLAY 0.680851 (-8625 2725);
DISPLAY INVISIBLE (-8625 2725);
FORCEPROP 1 LAST COMMENT_BODY TRUE
J 0
(-8225 2575);
DISPLAY 0.872340 (-8225 2575);
PAINT GREEN (-8225 2575);
DISPLAY INVISIBLE (-8225 2575);
FORCEPROP 1 LAST OFFPAGE TRUE
J 0
(-8025 2550);
DISPLAY 0.872340 (-8025 2550);
PAINT GREEN (-8025 2550);
DISPLAY INVISIBLE (-8025 2550);
FORCEPROP 2 LAST CDS_LIB mstr_standard
J 0
(-8350 2675);
DISPLAY 0.808511 (-8350 2675);
DISPLAY INVISIBLE (-8350 2675);
FORCEADD Q_RES..1
(-7775 2675);
FORCEPROP 1 LAST $LOCATION R1578
J 0
(-7825 2700);
DISPLAY 0.510638 (-7825 2700);
PAINT SKYBLUE (-7825 2700);
FORCEPROP 0 LAST CDS_LOCATION R1578
J 0
(-7825 2775);
DISPLAY 0.680851 (-7825 2775);
DISPLAY INVISIBLE (-7825 2775);
FORCEPROP 0 LAST $SEC 1
J 0
(-7825 2775);
DISPLAY 0.680851 (-7825 2775);
PAINT MONO (-7825 2775);
DISPLAY INVISIBLE (-7825 2775);
FORCEPROP 0 LAST CDS_SEC 1
J 0
(-7825 2775);
DISPLAY 0.680851 (-7825 2775);
DISPLAY INVISIBLE (-7825 2775);
FORCEPROP 1 LASTPIN (-7875 2675) $PN 1
J 0
(-7863 2687);
DISPLAY 0.787234 (-7863 2687);
PAINT MONO (-7863 2687);
FORCEPROP 1 LASTPIN (-7675 2675) $PN 2
J 0
(-7713 2687);
DISPLAY 0.787234 (-7713 2687);
PAINT MONO (-7713 2687);
FORCEPROP 1 LAST VALUE 49.9
J 2
(-7625 2725);
DISPLAY 0.510638 (-7625 2725);
PAINT SKYBLUE (-7625 2725);
FORCEPROP 2 LAST CDS_LIB pure_quanta
J 0
(-7775 2675);
DISPLAY INVISIBLE (-7775 2675);
FORCEPROP 1 LAST PATH I242
J 0
(-7825 2825);
DISPLAY 0.978723 (-7825 2825);
PAINT WHITE (-7825 2825);
DISPLAY INVISIBLE (-7825 2825);
FORCEPROP 1 LAST PART_NUMBER CS04992FB07
J 0
(-7825 2775);
DISPLAY 0.978723 (-7825 2775);
DISPLAY INVISIBLE (-7825 2775);
FORCEPROP 1 LAST TOLERANCE 1%
J 0
(-7775 2575);
DISPLAY 0.978723 (-7775 2575);
DISPLAY INVISIBLE (-7775 2575);
FORCEPROP 1 LAST WATTAGE 1/16W
J 2
(-7800 2525);
DISPLAY 0.978723 (-7800 2525);
DISPLAY INVISIBLE (-7800 2525);
FORCEPROP 1 LAST PACK_TYPE 0402LF
J 0
(-7525 2525);
DISPLAY 0.978723 (-7525 2525);
DISPLAY INVISIBLE (-7525 2525);
FORCEPROP 1 LAST MATERIAL CHIP
J 0
(-7775 2525);
DISPLAY 0.978723 (-7775 2525);
DISPLAY INVISIBLE (-7775 2525);
FORCEADD TAP..1
R 2
(-7725 3275);
FORCEPROP 3 LASTPIN (-7675 3275) SIG_NAME M_K_CPU0_SB_CB<2>
J 0
(-7665 3285);
DISPLAY 0.659574 (-7665 3285);
PAINT MONO (-7665 3285);
DISPLAY INVISIBLE (-7665 3285);
FORCEPROP 1 LASTPIN (-7675 3275) BN 2
J 2
(-7663 3283);
DISPLAY 0.489362 (-7663 3283);
PAINT GREEN (-7663 3283);
FORCEPROP 2 LAST CDS_LIB mstr_standard
J 0
(-7725 3275);
DISPLAY 0.723404 (-7725 3275);
PAINT MONO (-7725 3275);
DISPLAY INVISIBLE (-7725 3275);
FORCEPROP 1 LAST BODY_TYPE PLUMBING
J 2
(-7725 3325);
DISPLAY 0.872340 (-7725 3325);
PAINT GREEN (-7725 3325);
DISPLAY INVISIBLE (-7725 3325);
FORCEPROP 1 LAST HDL_TAP TRUE
J 2
(-8050 3150);
DISPLAY 0.872340 (-8050 3150);
DISPLAY INVISIBLE (-8050 3150);
FORCEPROP 1 LAST PATH I25
J 2
(-7723 3275);
DISPLAY 0.872340 (-7723 3275);
PAINT GREEN (-7723 3275);
DISPLAY INVISIBLE (-7723 3275);
FORCEADD TAP..1
R 2
(-7725 3375);
FORCEPROP 3 LASTPIN (-7675 3375) SIG_NAME M_K_CPU0_SB_CB<4>
J 0
(-7665 3385);
DISPLAY 0.659574 (-7665 3385);
PAINT MONO (-7665 3385);
DISPLAY INVISIBLE (-7665 3385);
FORCEPROP 1 LASTPIN (-7675 3375) BN 4
J 2
(-7663 3383);
DISPLAY 0.489362 (-7663 3383);
PAINT GREEN (-7663 3383);
FORCEPROP 2 LAST CDS_LIB mstr_standard
J 0
(-7725 3375);
DISPLAY 0.723404 (-7725 3375);
PAINT MONO (-7725 3375);
DISPLAY INVISIBLE (-7725 3375);
FORCEPROP 1 LAST BODY_TYPE PLUMBING
J 2
(-7725 3425);
DISPLAY 0.872340 (-7725 3425);
PAINT GREEN (-7725 3425);
DISPLAY INVISIBLE (-7725 3425);
FORCEPROP 1 LAST HDL_TAP TRUE
J 2
(-8050 3250);
DISPLAY 0.872340 (-8050 3250);
DISPLAY INVISIBLE (-8050 3250);
FORCEPROP 1 LAST PATH I26
J 2
(-7723 3375);
DISPLAY 0.872340 (-7723 3375);
PAINT GREEN (-7723 3375);
DISPLAY INVISIBLE (-7723 3375);
FORCEADD TAP..1
R 2
(-7725 3325);
FORCEPROP 3 LASTPIN (-7675 3325) SIG_NAME M_K_CPU0_SB_CB<3>
J 0
(-7665 3335);
DISPLAY 0.659574 (-7665 3335);
PAINT MONO (-7665 3335);
DISPLAY INVISIBLE (-7665 3335);
FORCEPROP 1 LASTPIN (-7675 3325) BN 3
J 2
(-7663 3333);
DISPLAY 0.489362 (-7663 3333);
PAINT GREEN (-7663 3333);
FORCEPROP 2 LAST CDS_LIB mstr_standard
J 0
(-7725 3325);
DISPLAY 0.723404 (-7725 3325);
PAINT MONO (-7725 3325);
DISPLAY INVISIBLE (-7725 3325);
FORCEPROP 1 LAST BODY_TYPE PLUMBING
J 2
(-7725 3375);
DISPLAY 0.872340 (-7725 3375);
PAINT GREEN (-7725 3375);
DISPLAY INVISIBLE (-7725 3375);
FORCEPROP 1 LAST HDL_TAP TRUE
J 2
(-8050 3200);
DISPLAY 0.872340 (-8050 3200);
DISPLAY INVISIBLE (-8050 3200);
FORCEPROP 1 LAST PATH I27
J 2
(-7723 3325);
DISPLAY 0.872340 (-7723 3325);
PAINT GREEN (-7723 3325);
DISPLAY INVISIBLE (-7723 3325);
FORCEADD TAP..1
R 2
(-7725 3425);
FORCEPROP 3 LASTPIN (-7675 3425) SIG_NAME M_K_CPU0_SB_CB<5>
J 0
(-7665 3435);
DISPLAY 0.659574 (-7665 3435);
PAINT MONO (-7665 3435);
DISPLAY INVISIBLE (-7665 3435);
FORCEPROP 1 LASTPIN (-7675 3425) BN 5
J 2
(-7663 3433);
DISPLAY 0.489362 (-7663 3433);
PAINT GREEN (-7663 3433);
FORCEPROP 2 LAST CDS_LIB mstr_standard
J 0
(-7725 3425);
DISPLAY 0.723404 (-7725 3425);
PAINT MONO (-7725 3425);
DISPLAY INVISIBLE (-7725 3425);
FORCEPROP 1 LAST BODY_TYPE PLUMBING
J 2
(-7725 3475);
DISPLAY 0.872340 (-7725 3475);
PAINT GREEN (-7725 3475);
DISPLAY INVISIBLE (-7725 3475);
FORCEPROP 1 LAST HDL_TAP TRUE
J 2
(-8050 3300);
DISPLAY 0.872340 (-8050 3300);
DISPLAY INVISIBLE (-8050 3300);
FORCEPROP 1 LAST PATH I28
J 2
(-7723 3425);
DISPLAY 0.872340 (-7723 3425);
PAINT GREEN (-7723 3425);
DISPLAY INVISIBLE (-7723 3425);
FORCEADD TAP..1
R 2
(-7725 3475);
FORCEPROP 3 LASTPIN (-7675 3475) SIG_NAME M_K_CPU0_SB_CB<6>
J 0
(-7665 3485);
DISPLAY 0.659574 (-7665 3485);
PAINT MONO (-7665 3485);
DISPLAY INVISIBLE (-7665 3485);
FORCEPROP 1 LASTPIN (-7675 3475) BN 6
J 2
(-7663 3483);
DISPLAY 0.489362 (-7663 3483);
PAINT GREEN (-7663 3483);
FORCEPROP 2 LAST CDS_LIB mstr_standard
J 0
(-7725 3475);
DISPLAY 0.723404 (-7725 3475);
PAINT MONO (-7725 3475);
DISPLAY INVISIBLE (-7725 3475);
FORCEPROP 1 LAST BODY_TYPE PLUMBING
J 2
(-7725 3525);
DISPLAY 0.872340 (-7725 3525);
PAINT GREEN (-7725 3525);
DISPLAY INVISIBLE (-7725 3525);
FORCEPROP 1 LAST HDL_TAP TRUE
J 2
(-8050 3350);
DISPLAY 0.872340 (-8050 3350);
DISPLAY INVISIBLE (-8050 3350);
FORCEPROP 1 LAST PATH I29
J 2
(-7723 3475);
DISPLAY 0.872340 (-7723 3475);
PAINT GREEN (-7723 3475);
DISPLAY INVISIBLE (-7723 3475);
FORCEADD TAP..1
R 2
(-7725 3525);
FORCEPROP 3 LASTPIN (-7675 3525) SIG_NAME M_K_CPU0_SB_CB<7>
J 0
(-7665 3535);
DISPLAY 0.659574 (-7665 3535);
PAINT MONO (-7665 3535);
DISPLAY INVISIBLE (-7665 3535);
FORCEPROP 1 LASTPIN (-7675 3525) BN 7
J 2
(-7663 3533);
DISPLAY 0.489362 (-7663 3533);
PAINT GREEN (-7663 3533);
FORCEPROP 2 LAST CDS_LIB mstr_standard
J 0
(-7725 3525);
DISPLAY 0.723404 (-7725 3525);
PAINT MONO (-7725 3525);
DISPLAY INVISIBLE (-7725 3525);
FORCEPROP 1 LAST BODY_TYPE PLUMBING
J 2
(-7725 3575);
DISPLAY 0.872340 (-7725 3575);
PAINT GREEN (-7725 3575);
DISPLAY INVISIBLE (-7725 3575);
FORCEPROP 1 LAST HDL_TAP TRUE
J 2
(-8050 3400);
DISPLAY 0.872340 (-8050 3400);
DISPLAY INVISIBLE (-8050 3400);
FORCEPROP 1 LAST PATH I30
J 2
(-7723 3525);
DISPLAY 0.872340 (-7723 3525);
PAINT GREEN (-7723 3525);
DISPLAY INVISIBLE (-7723 3525);
FORCEADD TAP..1
R 2
(-7725 3625);
FORCEPROP 3 LASTPIN (-7675 3625) SIG_NAME M_K_CPU0_SA_CB<0>
J 0
(-7665 3635);
DISPLAY 0.659574 (-7665 3635);
PAINT MONO (-7665 3635);
DISPLAY INVISIBLE (-7665 3635);
FORCEPROP 1 LASTPIN (-7675 3625) BN 0
J 2
(-7663 3633);
DISPLAY 0.489362 (-7663 3633);
PAINT GREEN (-7663 3633);
FORCEPROP 2 LAST CDS_LIB mstr_standard
J 0
(-7725 3625);
DISPLAY 0.723404 (-7725 3625);
PAINT MONO (-7725 3625);
DISPLAY INVISIBLE (-7725 3625);
FORCEPROP 1 LAST BODY_TYPE PLUMBING
J 2
(-7725 3675);
DISPLAY 0.872340 (-7725 3675);
PAINT GREEN (-7725 3675);
DISPLAY INVISIBLE (-7725 3675);
FORCEPROP 1 LAST HDL_TAP TRUE
J 2
(-8050 3500);
DISPLAY 0.872340 (-8050 3500);
DISPLAY INVISIBLE (-8050 3500);
FORCEPROP 1 LAST PATH I31
J 2
(-7723 3625);
DISPLAY 0.872340 (-7723 3625);
PAINT GREEN (-7723 3625);
DISPLAY INVISIBLE (-7723 3625);
FORCEADD TAP..1
R 2
(-7725 3675);
FORCEPROP 3 LASTPIN (-7675 3675) SIG_NAME M_K_CPU0_SA_CB<1>
J 0
(-7665 3685);
DISPLAY 0.659574 (-7665 3685);
PAINT MONO (-7665 3685);
DISPLAY INVISIBLE (-7665 3685);
FORCEPROP 1 LASTPIN (-7675 3675) BN 1
J 2
(-7663 3683);
DISPLAY 0.489362 (-7663 3683);
PAINT GREEN (-7663 3683);
FORCEPROP 2 LAST CDS_LIB mstr_standard
J 0
(-7725 3675);
DISPLAY 0.723404 (-7725 3675);
PAINT MONO (-7725 3675);
DISPLAY INVISIBLE (-7725 3675);
FORCEPROP 1 LAST BODY_TYPE PLUMBING
J 2
(-7725 3725);
DISPLAY 0.872340 (-7725 3725);
PAINT GREEN (-7725 3725);
DISPLAY INVISIBLE (-7725 3725);
FORCEPROP 1 LAST HDL_TAP TRUE
J 2
(-8050 3550);
DISPLAY 0.872340 (-8050 3550);
DISPLAY INVISIBLE (-8050 3550);
FORCEPROP 1 LAST PATH I32
J 2
(-7723 3675);
DISPLAY 0.872340 (-7723 3675);
PAINT GREEN (-7723 3675);
DISPLAY INVISIBLE (-7723 3675);
FORCEADD TAP..1
R 2
(-7725 3725);
FORCEPROP 3 LASTPIN (-7675 3725) SIG_NAME M_K_CPU0_SA_CB<2>
J 0
(-7665 3735);
DISPLAY 0.659574 (-7665 3735);
PAINT MONO (-7665 3735);
DISPLAY INVISIBLE (-7665 3735);
FORCEPROP 1 LASTPIN (-7675 3725) BN 2
J 2
(-7663 3733);
DISPLAY 0.489362 (-7663 3733);
PAINT GREEN (-7663 3733);
FORCEPROP 2 LAST CDS_LIB mstr_standard
J 0
(-7725 3725);
DISPLAY 0.723404 (-7725 3725);
PAINT MONO (-7725 3725);
DISPLAY INVISIBLE (-7725 3725);
FORCEPROP 1 LAST BODY_TYPE PLUMBING
J 2
(-7725 3775);
DISPLAY 0.872340 (-7725 3775);
PAINT GREEN (-7725 3775);
DISPLAY INVISIBLE (-7725 3775);
FORCEPROP 1 LAST HDL_TAP TRUE
J 2
(-8050 3600);
DISPLAY 0.872340 (-8050 3600);
DISPLAY INVISIBLE (-8050 3600);
FORCEPROP 1 LAST PATH I33
J 2
(-7723 3725);
DISPLAY 0.872340 (-7723 3725);
PAINT GREEN (-7723 3725);
DISPLAY INVISIBLE (-7723 3725);
FORCEADD TAP..1
R 2
(-7725 3775);
FORCEPROP 3 LASTPIN (-7675 3775) SIG_NAME M_K_CPU0_SA_CB<3>
J 0
(-7665 3785);
DISPLAY 0.659574 (-7665 3785);
PAINT MONO (-7665 3785);
DISPLAY INVISIBLE (-7665 3785);
FORCEPROP 1 LASTPIN (-7675 3775) BN 3
J 2
(-7663 3783);
DISPLAY 0.489362 (-7663 3783);
PAINT GREEN (-7663 3783);
FORCEPROP 2 LAST CDS_LIB mstr_standard
J 0
(-7725 3775);
DISPLAY 0.723404 (-7725 3775);
PAINT MONO (-7725 3775);
DISPLAY INVISIBLE (-7725 3775);
FORCEPROP 1 LAST BODY_TYPE PLUMBING
J 2
(-7725 3825);
DISPLAY 0.872340 (-7725 3825);
PAINT GREEN (-7725 3825);
DISPLAY INVISIBLE (-7725 3825);
FORCEPROP 1 LAST HDL_TAP TRUE
J 2
(-8050 3650);
DISPLAY 0.872340 (-8050 3650);
DISPLAY INVISIBLE (-8050 3650);
FORCEPROP 1 LAST PATH I34
J 2
(-7723 3775);
DISPLAY 0.872340 (-7723 3775);
PAINT GREEN (-7723 3775);
DISPLAY INVISIBLE (-7723 3775);
FORCEADD TAP..1
R 2
(-7725 3875);
FORCEPROP 3 LASTPIN (-7675 3875) SIG_NAME M_K_CPU0_SA_CB<5>
J 0
(-7665 3885);
DISPLAY 0.659574 (-7665 3885);
PAINT MONO (-7665 3885);
DISPLAY INVISIBLE (-7665 3885);
FORCEPROP 1 LASTPIN (-7675 3875) BN 5
J 2
(-7663 3883);
DISPLAY 0.489362 (-7663 3883);
PAINT GREEN (-7663 3883);
FORCEPROP 2 LAST CDS_LIB mstr_standard
J 0
(-7725 3875);
DISPLAY 0.723404 (-7725 3875);
PAINT MONO (-7725 3875);
DISPLAY INVISIBLE (-7725 3875);
FORCEPROP 1 LAST BODY_TYPE PLUMBING
J 2
(-7725 3925);
DISPLAY 0.872340 (-7725 3925);
PAINT GREEN (-7725 3925);
DISPLAY INVISIBLE (-7725 3925);
FORCEPROP 1 LAST HDL_TAP TRUE
J 2
(-8050 3750);
DISPLAY 0.872340 (-8050 3750);
DISPLAY INVISIBLE (-8050 3750);
FORCEPROP 1 LAST PATH I35
J 2
(-7723 3875);
DISPLAY 0.872340 (-7723 3875);
PAINT GREEN (-7723 3875);
DISPLAY INVISIBLE (-7723 3875);
FORCEADD TAP..1
R 2
(-7725 3825);
FORCEPROP 3 LASTPIN (-7675 3825) SIG_NAME M_K_CPU0_SA_CB<4>
J 0
(-7665 3835);
DISPLAY 0.659574 (-7665 3835);
PAINT MONO (-7665 3835);
DISPLAY INVISIBLE (-7665 3835);
FORCEPROP 1 LASTPIN (-7675 3825) BN 4
J 2
(-7663 3833);
DISPLAY 0.489362 (-7663 3833);
PAINT GREEN (-7663 3833);
FORCEPROP 2 LAST CDS_LIB mstr_standard
J 0
(-7725 3825);
DISPLAY 0.723404 (-7725 3825);
PAINT MONO (-7725 3825);
DISPLAY INVISIBLE (-7725 3825);
FORCEPROP 1 LAST BODY_TYPE PLUMBING
J 2
(-7725 3875);
DISPLAY 0.872340 (-7725 3875);
PAINT GREEN (-7725 3875);
DISPLAY INVISIBLE (-7725 3875);
FORCEPROP 1 LAST HDL_TAP TRUE
J 2
(-8050 3700);
DISPLAY 0.872340 (-8050 3700);
DISPLAY INVISIBLE (-8050 3700);
FORCEPROP 1 LAST PATH I36
J 2
(-7723 3825);
DISPLAY 0.872340 (-7723 3825);
PAINT GREEN (-7723 3825);
DISPLAY INVISIBLE (-7723 3825);
FORCEADD TAP..1
(-6025 2175);
FORCEPROP 3 LASTPIN (-6075 2175) SIG_NAME M_K_CPU0_SB_DQ<0>
J 0
(-6065 2185);
DISPLAY 0.659574 (-6065 2185);
PAINT MONO (-6065 2185);
DISPLAY INVISIBLE (-6065 2185);
FORCEPROP 1 LASTPIN (-6075 2175) BN 0
J 0
(-6087 2183);
DISPLAY 0.489362 (-6087 2183);
PAINT GREEN (-6087 2183);
FORCEPROP 2 LAST CDS_LIB mstr_standard
J 0
(-6025 2175);
DISPLAY 0.723404 (-6025 2175);
PAINT MONO (-6025 2175);
DISPLAY INVISIBLE (-6025 2175);
FORCEPROP 1 LAST BODY_TYPE PLUMBING
J 0
(-6025 2225);
DISPLAY 0.872340 (-6025 2225);
PAINT GREEN (-6025 2225);
DISPLAY INVISIBLE (-6025 2225);
FORCEPROP 1 LAST HDL_TAP TRUE
J 0
(-5700 2050);
DISPLAY 0.872340 (-5700 2050);
DISPLAY INVISIBLE (-5700 2050);
FORCEPROP 1 LAST PATH I37
J 0
(-6027 2175);
DISPLAY 0.872340 (-6027 2175);
PAINT GREEN (-6027 2175);
DISPLAY INVISIBLE (-6027 2175);
FORCEADD TAP..1
(-6025 2225);
FORCEPROP 3 LASTPIN (-6075 2225) SIG_NAME M_K_CPU0_SB_DQ<1>
J 0
(-6065 2235);
DISPLAY 0.659574 (-6065 2235);
PAINT MONO (-6065 2235);
DISPLAY INVISIBLE (-6065 2235);
FORCEPROP 1 LASTPIN (-6075 2225) BN 1
J 0
(-6087 2233);
DISPLAY 0.489362 (-6087 2233);
PAINT GREEN (-6087 2233);
FORCEPROP 2 LAST CDS_LIB mstr_standard
J 0
(-6025 2225);
DISPLAY 0.723404 (-6025 2225);
PAINT MONO (-6025 2225);
DISPLAY INVISIBLE (-6025 2225);
FORCEPROP 1 LAST BODY_TYPE PLUMBING
J 0
(-6025 2275);
DISPLAY 0.872340 (-6025 2275);
PAINT GREEN (-6025 2275);
DISPLAY INVISIBLE (-6025 2275);
FORCEPROP 1 LAST HDL_TAP TRUE
J 0
(-5700 2100);
DISPLAY 0.872340 (-5700 2100);
DISPLAY INVISIBLE (-5700 2100);
FORCEPROP 1 LAST PATH I38
J 0
(-6027 2225);
DISPLAY 0.872340 (-6027 2225);
PAINT GREEN (-6027 2225);
DISPLAY INVISIBLE (-6027 2225);
FORCEADD TAP..1
(-6025 2275);
FORCEPROP 3 LASTPIN (-6075 2275) SIG_NAME M_K_CPU0_SB_DQ<2>
J 0
(-6065 2285);
DISPLAY 0.659574 (-6065 2285);
PAINT MONO (-6065 2285);
DISPLAY INVISIBLE (-6065 2285);
FORCEPROP 1 LASTPIN (-6075 2275) BN 2
J 0
(-6087 2283);
DISPLAY 0.489362 (-6087 2283);
PAINT GREEN (-6087 2283);
FORCEPROP 2 LAST CDS_LIB mstr_standard
J 0
(-6025 2275);
DISPLAY 0.723404 (-6025 2275);
PAINT MONO (-6025 2275);
DISPLAY INVISIBLE (-6025 2275);
FORCEPROP 1 LAST BODY_TYPE PLUMBING
J 0
(-6025 2325);
DISPLAY 0.872340 (-6025 2325);
PAINT GREEN (-6025 2325);
DISPLAY INVISIBLE (-6025 2325);
FORCEPROP 1 LAST HDL_TAP TRUE
J 0
(-5700 2150);
DISPLAY 0.872340 (-5700 2150);
DISPLAY INVISIBLE (-5700 2150);
FORCEPROP 1 LAST PATH I39
J 0
(-6027 2275);
DISPLAY 0.872340 (-6027 2275);
PAINT GREEN (-6027 2275);
DISPLAY INVISIBLE (-6027 2275);
FORCEADD OFFPAGE..1
(-8325 2875);
FORCEPROP 2 LAST $XR0 95 
J 0
(-8546 2875);
DISPLAY 0.638298 (-8546 2875);
PAINT MONO (-8546 2875);
FORCEPROP 2 LAST PATH I4
J 0
(-8575 2925);
DISPLAY 1.021277 (-8575 2925);
DISPLAY INVISIBLE (-8575 2925);
FORCEPROP 1 LAST COMMENT_BODY TRUE
J 0
(-8200 2775);
DISPLAY 0.872340 (-8200 2775);
PAINT GREEN (-8200 2775);
DISPLAY INVISIBLE (-8200 2775);
FORCEPROP 1 LAST OFFPAGE TRUE
J 0
(-8000 2750);
DISPLAY 0.872340 (-8000 2750);
PAINT GREEN (-8000 2750);
DISPLAY INVISIBLE (-8000 2750);
FORCEPROP 2 LAST CDS_LIB mstr_standard
J 0
(-8325 2875);
DISPLAY 0.808511 (-8325 2875);
DISPLAY INVISIBLE (-8325 2875);
FORCEADD TAP..1
(-6025 2325);
FORCEPROP 3 LASTPIN (-6075 2325) SIG_NAME M_K_CPU0_SB_DQ<3>
J 0
(-6065 2335);
DISPLAY 0.659574 (-6065 2335);
PAINT MONO (-6065 2335);
DISPLAY INVISIBLE (-6065 2335);
FORCEPROP 1 LASTPIN (-6075 2325) BN 3
J 0
(-6087 2333);
DISPLAY 0.489362 (-6087 2333);
PAINT GREEN (-6087 2333);
FORCEPROP 2 LAST CDS_LIB mstr_standard
J 0
(-6025 2325);
DISPLAY 0.723404 (-6025 2325);
PAINT MONO (-6025 2325);
DISPLAY INVISIBLE (-6025 2325);
FORCEPROP 1 LAST BODY_TYPE PLUMBING
J 0
(-6025 2375);
DISPLAY 0.872340 (-6025 2375);
PAINT GREEN (-6025 2375);
DISPLAY INVISIBLE (-6025 2375);
FORCEPROP 1 LAST HDL_TAP TRUE
J 0
(-5700 2200);
DISPLAY 0.872340 (-5700 2200);
DISPLAY INVISIBLE (-5700 2200);
FORCEPROP 1 LAST PATH I40
J 0
(-6027 2325);
DISPLAY 0.872340 (-6027 2325);
PAINT GREEN (-6027 2325);
DISPLAY INVISIBLE (-6027 2325);
FORCEADD TAP..1
(-6025 2375);
FORCEPROP 3 LASTPIN (-6075 2375) SIG_NAME M_K_CPU0_SB_DQ<4>
J 0
(-6065 2385);
DISPLAY 0.659574 (-6065 2385);
PAINT MONO (-6065 2385);
DISPLAY INVISIBLE (-6065 2385);
FORCEPROP 1 LASTPIN (-6075 2375) BN 4
J 0
(-6087 2383);
DISPLAY 0.489362 (-6087 2383);
PAINT GREEN (-6087 2383);
FORCEPROP 2 LAST CDS_LIB mstr_standard
J 0
(-6025 2375);
DISPLAY 0.723404 (-6025 2375);
PAINT MONO (-6025 2375);
DISPLAY INVISIBLE (-6025 2375);
FORCEPROP 1 LAST BODY_TYPE PLUMBING
J 0
(-6025 2425);
DISPLAY 0.872340 (-6025 2425);
PAINT GREEN (-6025 2425);
DISPLAY INVISIBLE (-6025 2425);
FORCEPROP 1 LAST HDL_TAP TRUE
J 0
(-5700 2250);
DISPLAY 0.872340 (-5700 2250);
DISPLAY INVISIBLE (-5700 2250);
FORCEPROP 1 LAST PATH I41
J 0
(-6027 2375);
DISPLAY 0.872340 (-6027 2375);
PAINT GREEN (-6027 2375);
DISPLAY INVISIBLE (-6027 2375);
FORCEADD TAP..1
(-6025 2475);
FORCEPROP 3 LASTPIN (-6075 2475) SIG_NAME M_K_CPU0_SB_DQ<6>
J 0
(-6065 2485);
DISPLAY 0.659574 (-6065 2485);
PAINT MONO (-6065 2485);
DISPLAY INVISIBLE (-6065 2485);
FORCEPROP 1 LASTPIN (-6075 2475) BN 6
J 0
(-6087 2483);
DISPLAY 0.489362 (-6087 2483);
PAINT GREEN (-6087 2483);
FORCEPROP 2 LAST CDS_LIB mstr_standard
J 0
(-6025 2475);
DISPLAY 0.723404 (-6025 2475);
PAINT MONO (-6025 2475);
DISPLAY INVISIBLE (-6025 2475);
FORCEPROP 1 LAST BODY_TYPE PLUMBING
J 0
(-6025 2525);
DISPLAY 0.872340 (-6025 2525);
PAINT GREEN (-6025 2525);
DISPLAY INVISIBLE (-6025 2525);
FORCEPROP 1 LAST HDL_TAP TRUE
J 0
(-5700 2350);
DISPLAY 0.872340 (-5700 2350);
DISPLAY INVISIBLE (-5700 2350);
FORCEPROP 1 LAST PATH I42
J 0
(-6027 2475);
DISPLAY 0.872340 (-6027 2475);
PAINT GREEN (-6027 2475);
DISPLAY INVISIBLE (-6027 2475);
FORCEADD TAP..1
(-6025 2425);
FORCEPROP 3 LASTPIN (-6075 2425) SIG_NAME M_K_CPU0_SB_DQ<5>
J 0
(-6065 2435);
DISPLAY 0.659574 (-6065 2435);
PAINT MONO (-6065 2435);
DISPLAY INVISIBLE (-6065 2435);
FORCEPROP 1 LASTPIN (-6075 2425) BN 5
J 0
(-6087 2433);
DISPLAY 0.489362 (-6087 2433);
PAINT GREEN (-6087 2433);
FORCEPROP 2 LAST CDS_LIB mstr_standard
J 0
(-6025 2425);
DISPLAY 0.723404 (-6025 2425);
PAINT MONO (-6025 2425);
DISPLAY INVISIBLE (-6025 2425);
FORCEPROP 1 LAST BODY_TYPE PLUMBING
J 0
(-6025 2475);
DISPLAY 0.872340 (-6025 2475);
PAINT GREEN (-6025 2475);
DISPLAY INVISIBLE (-6025 2475);
FORCEPROP 1 LAST HDL_TAP TRUE
J 0
(-5700 2300);
DISPLAY 0.872340 (-5700 2300);
DISPLAY INVISIBLE (-5700 2300);
FORCEPROP 1 LAST PATH I43
J 0
(-6027 2425);
DISPLAY 0.872340 (-6027 2425);
PAINT GREEN (-6027 2425);
DISPLAY INVISIBLE (-6027 2425);
FORCEADD TAP..1
(-6025 2575);
FORCEPROP 3 LASTPIN (-6075 2575) SIG_NAME M_K_CPU0_SB_DQ<8>
J 0
(-6065 2585);
DISPLAY 0.659574 (-6065 2585);
PAINT MONO (-6065 2585);
DISPLAY INVISIBLE (-6065 2585);
FORCEPROP 1 LASTPIN (-6075 2575) BN 8
J 0
(-6087 2583);
DISPLAY 0.489362 (-6087 2583);
PAINT GREEN (-6087 2583);
FORCEPROP 2 LAST CDS_LIB mstr_standard
J 0
(-6025 2575);
DISPLAY 0.723404 (-6025 2575);
PAINT MONO (-6025 2575);
DISPLAY INVISIBLE (-6025 2575);
FORCEPROP 1 LAST BODY_TYPE PLUMBING
J 0
(-6025 2625);
DISPLAY 0.872340 (-6025 2625);
PAINT GREEN (-6025 2625);
DISPLAY INVISIBLE (-6025 2625);
FORCEPROP 1 LAST HDL_TAP TRUE
J 0
(-5700 2450);
DISPLAY 0.872340 (-5700 2450);
DISPLAY INVISIBLE (-5700 2450);
FORCEPROP 1 LAST PATH I44
J 0
(-6027 2575);
DISPLAY 0.872340 (-6027 2575);
PAINT GREEN (-6027 2575);
DISPLAY INVISIBLE (-6027 2575);
FORCEADD TAP..1
(-6025 2525);
FORCEPROP 3 LASTPIN (-6075 2525) SIG_NAME M_K_CPU0_SB_DQ<7>
J 0
(-6065 2535);
DISPLAY 0.659574 (-6065 2535);
PAINT MONO (-6065 2535);
DISPLAY INVISIBLE (-6065 2535);
FORCEPROP 1 LASTPIN (-6075 2525) BN 7
J 0
(-6087 2533);
DISPLAY 0.489362 (-6087 2533);
PAINT GREEN (-6087 2533);
FORCEPROP 2 LAST CDS_LIB mstr_standard
J 0
(-6025 2525);
DISPLAY 0.723404 (-6025 2525);
PAINT MONO (-6025 2525);
DISPLAY INVISIBLE (-6025 2525);
FORCEPROP 1 LAST BODY_TYPE PLUMBING
J 0
(-6025 2575);
DISPLAY 0.872340 (-6025 2575);
PAINT GREEN (-6025 2575);
DISPLAY INVISIBLE (-6025 2575);
FORCEPROP 1 LAST HDL_TAP TRUE
J 0
(-5700 2400);
DISPLAY 0.872340 (-5700 2400);
DISPLAY INVISIBLE (-5700 2400);
FORCEPROP 1 LAST PATH I45
J 0
(-6027 2525);
DISPLAY 0.872340 (-6027 2525);
PAINT GREEN (-6027 2525);
DISPLAY INVISIBLE (-6027 2525);
FORCEADD TAP..1
(-6025 2625);
FORCEPROP 3 LASTPIN (-6075 2625) SIG_NAME M_K_CPU0_SB_DQ<9>
J 0
(-6065 2635);
DISPLAY 0.659574 (-6065 2635);
PAINT MONO (-6065 2635);
DISPLAY INVISIBLE (-6065 2635);
FORCEPROP 1 LASTPIN (-6075 2625) BN 9
J 0
(-6087 2633);
DISPLAY 0.489362 (-6087 2633);
PAINT GREEN (-6087 2633);
FORCEPROP 2 LAST CDS_LIB mstr_standard
J 0
(-6025 2625);
DISPLAY 0.723404 (-6025 2625);
PAINT MONO (-6025 2625);
DISPLAY INVISIBLE (-6025 2625);
FORCEPROP 1 LAST BODY_TYPE PLUMBING
J 0
(-6025 2675);
DISPLAY 0.872340 (-6025 2675);
PAINT GREEN (-6025 2675);
DISPLAY INVISIBLE (-6025 2675);
FORCEPROP 1 LAST HDL_TAP TRUE
J 0
(-5700 2500);
DISPLAY 0.872340 (-5700 2500);
DISPLAY INVISIBLE (-5700 2500);
FORCEPROP 1 LAST PATH I46
J 0
(-6027 2625);
DISPLAY 0.872340 (-6027 2625);
PAINT GREEN (-6027 2625);
DISPLAY INVISIBLE (-6027 2625);
FORCEADD TAP..1
(-6025 2725);
FORCEPROP 3 LASTPIN (-6075 2725) SIG_NAME M_K_CPU0_SB_DQ<11>
J 0
(-6065 2735);
DISPLAY 0.659574 (-6065 2735);
PAINT MONO (-6065 2735);
DISPLAY INVISIBLE (-6065 2735);
FORCEPROP 1 LASTPIN (-6075 2725) BN 11
J 0
(-6087 2733);
DISPLAY 0.489362 (-6087 2733);
PAINT GREEN (-6087 2733);
FORCEPROP 2 LAST CDS_LIB mstr_standard
J 0
(-6025 2725);
DISPLAY 0.723404 (-6025 2725);
PAINT MONO (-6025 2725);
DISPLAY INVISIBLE (-6025 2725);
FORCEPROP 1 LAST BODY_TYPE PLUMBING
J 0
(-6025 2775);
DISPLAY 0.872340 (-6025 2775);
PAINT GREEN (-6025 2775);
DISPLAY INVISIBLE (-6025 2775);
FORCEPROP 1 LAST HDL_TAP TRUE
J 0
(-5700 2600);
DISPLAY 0.872340 (-5700 2600);
DISPLAY INVISIBLE (-5700 2600);
FORCEPROP 1 LAST PATH I47
J 0
(-6027 2725);
DISPLAY 0.872340 (-6027 2725);
PAINT GREEN (-6027 2725);
DISPLAY INVISIBLE (-6027 2725);
FORCEADD TAP..1
(-6025 2675);
FORCEPROP 3 LASTPIN (-6075 2675) SIG_NAME M_K_CPU0_SB_DQ<10>
J 0
(-6065 2685);
DISPLAY 0.659574 (-6065 2685);
PAINT MONO (-6065 2685);
DISPLAY INVISIBLE (-6065 2685);
FORCEPROP 1 LASTPIN (-6075 2675) BN 10
J 0
(-6087 2683);
DISPLAY 0.489362 (-6087 2683);
PAINT GREEN (-6087 2683);
FORCEPROP 2 LAST CDS_LIB mstr_standard
J 0
(-6025 2675);
DISPLAY 0.723404 (-6025 2675);
PAINT MONO (-6025 2675);
DISPLAY INVISIBLE (-6025 2675);
FORCEPROP 1 LAST BODY_TYPE PLUMBING
J 0
(-6025 2725);
DISPLAY 0.872340 (-6025 2725);
PAINT GREEN (-6025 2725);
DISPLAY INVISIBLE (-6025 2725);
FORCEPROP 1 LAST HDL_TAP TRUE
J 0
(-5700 2550);
DISPLAY 0.872340 (-5700 2550);
DISPLAY INVISIBLE (-5700 2550);
FORCEPROP 1 LAST PATH I48
J 0
(-6027 2675);
DISPLAY 0.872340 (-6027 2675);
PAINT GREEN (-6027 2675);
DISPLAY INVISIBLE (-6027 2675);
FORCEADD TAP..1
(-6025 2775);
FORCEPROP 3 LASTPIN (-6075 2775) SIG_NAME M_K_CPU0_SB_DQ<12>
J 0
(-6065 2785);
DISPLAY 0.659574 (-6065 2785);
PAINT MONO (-6065 2785);
DISPLAY INVISIBLE (-6065 2785);
FORCEPROP 1 LASTPIN (-6075 2775) BN 12
J 0
(-6087 2783);
DISPLAY 0.489362 (-6087 2783);
PAINT GREEN (-6087 2783);
FORCEPROP 2 LAST CDS_LIB mstr_standard
J 0
(-6025 2775);
DISPLAY 0.723404 (-6025 2775);
PAINT MONO (-6025 2775);
DISPLAY INVISIBLE (-6025 2775);
FORCEPROP 1 LAST BODY_TYPE PLUMBING
J 0
(-6025 2825);
DISPLAY 0.872340 (-6025 2825);
PAINT GREEN (-6025 2825);
DISPLAY INVISIBLE (-6025 2825);
FORCEPROP 1 LAST HDL_TAP TRUE
J 0
(-5700 2650);
DISPLAY 0.872340 (-5700 2650);
DISPLAY INVISIBLE (-5700 2650);
FORCEPROP 1 LAST PATH I49
J 0
(-6027 2775);
DISPLAY 0.872340 (-6027 2775);
PAINT GREEN (-6027 2775);
DISPLAY INVISIBLE (-6027 2775);
FORCEADD OFFPAGE..5
(-8325 1975);
FORCEPROP 2 LAST $XR0 20 
J 0
(-8549 1975);
DISPLAY 0.638298 (-8549 1975);
PAINT MONO (-8549 1975);
FORCEPROP 2 LAST PATH I5
J 0
(-8275 2050);
DISPLAY 1.021277 (-8275 2050);
DISPLAY INVISIBLE (-8275 2050);
FORCEPROP 1 LAST COMMENT_BODY TRUE
J 0
(-8225 1900);
DISPLAY 0.872340 (-8225 1900);
PAINT GREEN (-8225 1900);
DISPLAY INVISIBLE (-8225 1900);
FORCEPROP 1 LAST OFFPAGE TRUE
J 0
(-8000 1850);
DISPLAY 0.872340 (-8000 1850);
PAINT GREEN (-8000 1850);
DISPLAY INVISIBLE (-8000 1850);
FORCEPROP 2 LAST CDS_LIB mstr_standard
J 0
(-8325 1975);
DISPLAY 0.808511 (-8325 1975);
DISPLAY INVISIBLE (-8325 1975);
FORCEADD TAP..1
(-6025 2825);
FORCEPROP 3 LASTPIN (-6075 2825) SIG_NAME M_K_CPU0_SB_DQ<13>
J 0
(-6065 2835);
DISPLAY 0.659574 (-6065 2835);
PAINT MONO (-6065 2835);
DISPLAY INVISIBLE (-6065 2835);
FORCEPROP 1 LASTPIN (-6075 2825) BN 13
J 0
(-6087 2833);
DISPLAY 0.489362 (-6087 2833);
PAINT GREEN (-6087 2833);
FORCEPROP 2 LAST CDS_LIB mstr_standard
J 0
(-6025 2825);
DISPLAY 0.723404 (-6025 2825);
PAINT MONO (-6025 2825);
DISPLAY INVISIBLE (-6025 2825);
FORCEPROP 1 LAST BODY_TYPE PLUMBING
J 0
(-6025 2875);
DISPLAY 0.872340 (-6025 2875);
PAINT GREEN (-6025 2875);
DISPLAY INVISIBLE (-6025 2875);
FORCEPROP 1 LAST HDL_TAP TRUE
J 0
(-5700 2700);
DISPLAY 0.872340 (-5700 2700);
DISPLAY INVISIBLE (-5700 2700);
FORCEPROP 1 LAST PATH I50
J 0
(-6027 2825);
DISPLAY 0.872340 (-6027 2825);
PAINT GREEN (-6027 2825);
DISPLAY INVISIBLE (-6027 2825);
FORCEADD TAP..1
(-6025 2875);
FORCEPROP 3 LASTPIN (-6075 2875) SIG_NAME M_K_CPU0_SB_DQ<14>
J 0
(-6065 2885);
DISPLAY 0.659574 (-6065 2885);
PAINT MONO (-6065 2885);
DISPLAY INVISIBLE (-6065 2885);
FORCEPROP 1 LASTPIN (-6075 2875) BN 14
J 0
(-6087 2883);
DISPLAY 0.489362 (-6087 2883);
PAINT GREEN (-6087 2883);
FORCEPROP 2 LAST CDS_LIB mstr_standard
J 0
(-6025 2875);
DISPLAY 0.723404 (-6025 2875);
PAINT MONO (-6025 2875);
DISPLAY INVISIBLE (-6025 2875);
FORCEPROP 1 LAST BODY_TYPE PLUMBING
J 0
(-6025 2925);
DISPLAY 0.872340 (-6025 2925);
PAINT GREEN (-6025 2925);
DISPLAY INVISIBLE (-6025 2925);
FORCEPROP 1 LAST HDL_TAP TRUE
J 0
(-5700 2750);
DISPLAY 0.872340 (-5700 2750);
DISPLAY INVISIBLE (-5700 2750);
FORCEPROP 1 LAST PATH I51
J 0
(-6027 2875);
DISPLAY 0.872340 (-6027 2875);
PAINT GREEN (-6027 2875);
DISPLAY INVISIBLE (-6027 2875);
FORCEADD TAP..1
(-6025 2975);
FORCEPROP 3 LASTPIN (-6075 2975) SIG_NAME M_K_CPU0_SB_DQ<16>
J 0
(-6065 2985);
DISPLAY 0.659574 (-6065 2985);
PAINT MONO (-6065 2985);
DISPLAY INVISIBLE (-6065 2985);
FORCEPROP 1 LASTPIN (-6075 2975) BN 16
J 0
(-6087 2983);
DISPLAY 0.489362 (-6087 2983);
PAINT GREEN (-6087 2983);
FORCEPROP 2 LAST CDS_LIB mstr_standard
J 0
(-6025 2975);
DISPLAY 0.723404 (-6025 2975);
PAINT MONO (-6025 2975);
DISPLAY INVISIBLE (-6025 2975);
FORCEPROP 1 LAST BODY_TYPE PLUMBING
J 0
(-6025 3025);
DISPLAY 0.872340 (-6025 3025);
PAINT GREEN (-6025 3025);
DISPLAY INVISIBLE (-6025 3025);
FORCEPROP 1 LAST HDL_TAP TRUE
J 0
(-5700 2850);
DISPLAY 0.872340 (-5700 2850);
DISPLAY INVISIBLE (-5700 2850);
FORCEPROP 1 LAST PATH I52
J 0
(-6027 2975);
DISPLAY 0.872340 (-6027 2975);
PAINT GREEN (-6027 2975);
DISPLAY INVISIBLE (-6027 2975);
FORCEADD TAP..1
(-6025 2925);
FORCEPROP 3 LASTPIN (-6075 2925) SIG_NAME M_K_CPU0_SB_DQ<15>
J 0
(-6065 2935);
DISPLAY 0.659574 (-6065 2935);
PAINT MONO (-6065 2935);
DISPLAY INVISIBLE (-6065 2935);
FORCEPROP 1 LASTPIN (-6075 2925) BN 15
J 0
(-6087 2933);
DISPLAY 0.489362 (-6087 2933);
PAINT GREEN (-6087 2933);
FORCEPROP 2 LAST CDS_LIB mstr_standard
J 0
(-6025 2925);
DISPLAY 0.723404 (-6025 2925);
PAINT MONO (-6025 2925);
DISPLAY INVISIBLE (-6025 2925);
FORCEPROP 1 LAST BODY_TYPE PLUMBING
J 0
(-6025 2975);
DISPLAY 0.872340 (-6025 2975);
PAINT GREEN (-6025 2975);
DISPLAY INVISIBLE (-6025 2975);
FORCEPROP 1 LAST HDL_TAP TRUE
J 0
(-5700 2800);
DISPLAY 0.872340 (-5700 2800);
DISPLAY INVISIBLE (-5700 2800);
FORCEPROP 1 LAST PATH I53
J 0
(-6027 2925);
DISPLAY 0.872340 (-6027 2925);
PAINT GREEN (-6027 2925);
DISPLAY INVISIBLE (-6027 2925);
FORCEADD TAP..1
(-6025 3025);
FORCEPROP 3 LASTPIN (-6075 3025) SIG_NAME M_K_CPU0_SB_DQ<17>
J 0
(-6065 3035);
DISPLAY 0.659574 (-6065 3035);
PAINT MONO (-6065 3035);
DISPLAY INVISIBLE (-6065 3035);
FORCEPROP 1 LASTPIN (-6075 3025) BN 17
J 0
(-6087 3033);
DISPLAY 0.489362 (-6087 3033);
PAINT GREEN (-6087 3033);
FORCEPROP 2 LAST CDS_LIB mstr_standard
J 0
(-6025 3025);
DISPLAY 0.723404 (-6025 3025);
PAINT MONO (-6025 3025);
DISPLAY INVISIBLE (-6025 3025);
FORCEPROP 1 LAST BODY_TYPE PLUMBING
J 0
(-6025 3075);
DISPLAY 0.872340 (-6025 3075);
PAINT GREEN (-6025 3075);
DISPLAY INVISIBLE (-6025 3075);
FORCEPROP 1 LAST HDL_TAP TRUE
J 0
(-5700 2900);
DISPLAY 0.872340 (-5700 2900);
DISPLAY INVISIBLE (-5700 2900);
FORCEPROP 1 LAST PATH I54
J 0
(-6027 3025);
DISPLAY 0.872340 (-6027 3025);
PAINT GREEN (-6027 3025);
DISPLAY INVISIBLE (-6027 3025);
FORCEADD TAP..1
(-6025 3075);
FORCEPROP 3 LASTPIN (-6075 3075) SIG_NAME M_K_CPU0_SB_DQ<18>
J 0
(-6065 3085);
DISPLAY 0.659574 (-6065 3085);
PAINT MONO (-6065 3085);
DISPLAY INVISIBLE (-6065 3085);
FORCEPROP 1 LASTPIN (-6075 3075) BN 18
J 0
(-6087 3083);
DISPLAY 0.489362 (-6087 3083);
PAINT GREEN (-6087 3083);
FORCEPROP 2 LAST CDS_LIB mstr_standard
J 0
(-6025 3075);
DISPLAY 0.723404 (-6025 3075);
PAINT MONO (-6025 3075);
DISPLAY INVISIBLE (-6025 3075);
FORCEPROP 1 LAST BODY_TYPE PLUMBING
J 0
(-6025 3125);
DISPLAY 0.872340 (-6025 3125);
PAINT GREEN (-6025 3125);
DISPLAY INVISIBLE (-6025 3125);
FORCEPROP 1 LAST HDL_TAP TRUE
J 0
(-5700 2950);
DISPLAY 0.872340 (-5700 2950);
DISPLAY INVISIBLE (-5700 2950);
FORCEPROP 1 LAST PATH I55
J 0
(-6027 3075);
DISPLAY 0.872340 (-6027 3075);
PAINT GREEN (-6027 3075);
DISPLAY INVISIBLE (-6027 3075);
FORCEADD TAP..1
(-6025 3125);
FORCEPROP 3 LASTPIN (-6075 3125) SIG_NAME M_K_CPU0_SB_DQ<19>
J 0
(-6065 3135);
DISPLAY 0.659574 (-6065 3135);
PAINT MONO (-6065 3135);
DISPLAY INVISIBLE (-6065 3135);
FORCEPROP 1 LASTPIN (-6075 3125) BN 19
J 0
(-6087 3133);
DISPLAY 0.489362 (-6087 3133);
PAINT GREEN (-6087 3133);
FORCEPROP 2 LAST CDS_LIB mstr_standard
J 0
(-6025 3125);
DISPLAY 0.723404 (-6025 3125);
PAINT MONO (-6025 3125);
DISPLAY INVISIBLE (-6025 3125);
FORCEPROP 1 LAST BODY_TYPE PLUMBING
J 0
(-6025 3175);
DISPLAY 0.872340 (-6025 3175);
PAINT GREEN (-6025 3175);
DISPLAY INVISIBLE (-6025 3175);
FORCEPROP 1 LAST HDL_TAP TRUE
J 0
(-5700 3000);
DISPLAY 0.872340 (-5700 3000);
DISPLAY INVISIBLE (-5700 3000);
FORCEPROP 1 LAST PATH I56
J 0
(-6027 3125);
DISPLAY 0.872340 (-6027 3125);
PAINT GREEN (-6027 3125);
DISPLAY INVISIBLE (-6027 3125);
FORCEADD TAP..1
(-6025 3175);
FORCEPROP 3 LASTPIN (-6075 3175) SIG_NAME M_K_CPU0_SB_DQ<20>
J 0
(-6065 3185);
DISPLAY 0.659574 (-6065 3185);
PAINT MONO (-6065 3185);
DISPLAY INVISIBLE (-6065 3185);
FORCEPROP 1 LASTPIN (-6075 3175) BN 20
J 0
(-6087 3183);
DISPLAY 0.489362 (-6087 3183);
PAINT GREEN (-6087 3183);
FORCEPROP 2 LAST CDS_LIB mstr_standard
J 0
(-6025 3175);
DISPLAY 0.723404 (-6025 3175);
PAINT MONO (-6025 3175);
DISPLAY INVISIBLE (-6025 3175);
FORCEPROP 1 LAST BODY_TYPE PLUMBING
J 0
(-6025 3225);
DISPLAY 0.872340 (-6025 3225);
PAINT GREEN (-6025 3225);
DISPLAY INVISIBLE (-6025 3225);
FORCEPROP 1 LAST HDL_TAP TRUE
J 0
(-5700 3050);
DISPLAY 0.872340 (-5700 3050);
DISPLAY INVISIBLE (-5700 3050);
FORCEPROP 1 LAST PATH I57
J 0
(-6027 3175);
DISPLAY 0.872340 (-6027 3175);
PAINT GREEN (-6027 3175);
DISPLAY INVISIBLE (-6027 3175);
FORCEADD TAP..1
(-6025 3225);
FORCEPROP 3 LASTPIN (-6075 3225) SIG_NAME M_K_CPU0_SB_DQ<21>
J 0
(-6065 3235);
DISPLAY 0.659574 (-6065 3235);
PAINT MONO (-6065 3235);
DISPLAY INVISIBLE (-6065 3235);
FORCEPROP 1 LASTPIN (-6075 3225) BN 21
J 0
(-6087 3233);
DISPLAY 0.489362 (-6087 3233);
PAINT GREEN (-6087 3233);
FORCEPROP 2 LAST CDS_LIB mstr_standard
J 0
(-6025 3225);
DISPLAY 0.723404 (-6025 3225);
PAINT MONO (-6025 3225);
DISPLAY INVISIBLE (-6025 3225);
FORCEPROP 1 LAST BODY_TYPE PLUMBING
J 0
(-6025 3275);
DISPLAY 0.872340 (-6025 3275);
PAINT GREEN (-6025 3275);
DISPLAY INVISIBLE (-6025 3275);
FORCEPROP 1 LAST HDL_TAP TRUE
J 0
(-5700 3100);
DISPLAY 0.872340 (-5700 3100);
DISPLAY INVISIBLE (-5700 3100);
FORCEPROP 1 LAST PATH I58
J 0
(-6027 3225);
DISPLAY 0.872340 (-6027 3225);
PAINT GREEN (-6027 3225);
DISPLAY INVISIBLE (-6027 3225);
FORCEADD TAP..1
(-6025 3275);
FORCEPROP 3 LASTPIN (-6075 3275) SIG_NAME M_K_CPU0_SB_DQ<22>
J 0
(-6065 3285);
DISPLAY 0.659574 (-6065 3285);
PAINT MONO (-6065 3285);
DISPLAY INVISIBLE (-6065 3285);
FORCEPROP 1 LASTPIN (-6075 3275) BN 22
J 0
(-6087 3283);
DISPLAY 0.489362 (-6087 3283);
PAINT GREEN (-6087 3283);
FORCEPROP 2 LAST CDS_LIB mstr_standard
J 0
(-6025 3275);
DISPLAY 0.723404 (-6025 3275);
PAINT MONO (-6025 3275);
DISPLAY INVISIBLE (-6025 3275);
FORCEPROP 1 LAST BODY_TYPE PLUMBING
J 0
(-6025 3325);
DISPLAY 0.872340 (-6025 3325);
PAINT GREEN (-6025 3325);
DISPLAY INVISIBLE (-6025 3325);
FORCEPROP 1 LAST HDL_TAP TRUE
J 0
(-5700 3150);
DISPLAY 0.872340 (-5700 3150);
DISPLAY INVISIBLE (-5700 3150);
FORCEPROP 1 LAST PATH I59
J 0
(-6027 3275);
DISPLAY 0.872340 (-6027 3275);
PAINT GREEN (-6027 3275);
DISPLAY INVISIBLE (-6027 3275);
FORCEADD OFFPAGE..5
(-8325 1925);
FORCEPROP 2 LAST $XR0 20 
J 0
(-8549 1925);
DISPLAY 0.638298 (-8549 1925);
PAINT MONO (-8549 1925);
FORCEPROP 2 LAST PATH I6
J 0
(-8275 2000);
DISPLAY 1.021277 (-8275 2000);
DISPLAY INVISIBLE (-8275 2000);
FORCEPROP 1 LAST COMMENT_BODY TRUE
J 0
(-8225 1850);
DISPLAY 0.872340 (-8225 1850);
PAINT GREEN (-8225 1850);
DISPLAY INVISIBLE (-8225 1850);
FORCEPROP 1 LAST OFFPAGE TRUE
J 0
(-8000 1800);
DISPLAY 0.872340 (-8000 1800);
PAINT GREEN (-8000 1800);
DISPLAY INVISIBLE (-8000 1800);
FORCEPROP 2 LAST CDS_LIB mstr_standard
J 0
(-8325 1925);
DISPLAY 0.808511 (-8325 1925);
DISPLAY INVISIBLE (-8325 1925);
FORCEADD TAP..1
(-6025 3375);
FORCEPROP 3 LASTPIN (-6075 3375) SIG_NAME M_K_CPU0_SB_DQ<24>
J 0
(-6065 3385);
DISPLAY 0.659574 (-6065 3385);
PAINT MONO (-6065 3385);
DISPLAY INVISIBLE (-6065 3385);
FORCEPROP 1 LASTPIN (-6075 3375) BN 24
J 0
(-6087 3383);
DISPLAY 0.489362 (-6087 3383);
PAINT GREEN (-6087 3383);
FORCEPROP 2 LAST CDS_LIB mstr_standard
J 0
(-6025 3375);
DISPLAY 0.723404 (-6025 3375);
PAINT MONO (-6025 3375);
DISPLAY INVISIBLE (-6025 3375);
FORCEPROP 1 LAST BODY_TYPE PLUMBING
J 0
(-6025 3425);
DISPLAY 0.872340 (-6025 3425);
PAINT GREEN (-6025 3425);
DISPLAY INVISIBLE (-6025 3425);
FORCEPROP 1 LAST HDL_TAP TRUE
J 0
(-5700 3250);
DISPLAY 0.872340 (-5700 3250);
DISPLAY INVISIBLE (-5700 3250);
FORCEPROP 1 LAST PATH I60
J 0
(-6027 3375);
DISPLAY 0.872340 (-6027 3375);
PAINT GREEN (-6027 3375);
DISPLAY INVISIBLE (-6027 3375);
FORCEADD TAP..1
(-6025 3325);
FORCEPROP 3 LASTPIN (-6075 3325) SIG_NAME M_K_CPU0_SB_DQ<23>
J 0
(-6065 3335);
DISPLAY 0.659574 (-6065 3335);
PAINT MONO (-6065 3335);
DISPLAY INVISIBLE (-6065 3335);
FORCEPROP 1 LASTPIN (-6075 3325) BN 23
J 0
(-6087 3333);
DISPLAY 0.489362 (-6087 3333);
PAINT GREEN (-6087 3333);
FORCEPROP 2 LAST CDS_LIB mstr_standard
J 0
(-6025 3325);
DISPLAY 0.723404 (-6025 3325);
PAINT MONO (-6025 3325);
DISPLAY INVISIBLE (-6025 3325);
FORCEPROP 1 LAST BODY_TYPE PLUMBING
J 0
(-6025 3375);
DISPLAY 0.872340 (-6025 3375);
PAINT GREEN (-6025 3375);
DISPLAY INVISIBLE (-6025 3375);
FORCEPROP 1 LAST HDL_TAP TRUE
J 0
(-5700 3200);
DISPLAY 0.872340 (-5700 3200);
DISPLAY INVISIBLE (-5700 3200);
FORCEPROP 1 LAST PATH I61
J 0
(-6027 3325);
DISPLAY 0.872340 (-6027 3325);
PAINT GREEN (-6027 3325);
DISPLAY INVISIBLE (-6027 3325);
FORCEADD TAP..1
(-6025 3425);
FORCEPROP 3 LASTPIN (-6075 3425) SIG_NAME M_K_CPU0_SB_DQ<25>
J 0
(-6065 3435);
DISPLAY 0.659574 (-6065 3435);
PAINT MONO (-6065 3435);
DISPLAY INVISIBLE (-6065 3435);
FORCEPROP 1 LASTPIN (-6075 3425) BN 25
J 0
(-6087 3433);
DISPLAY 0.489362 (-6087 3433);
PAINT GREEN (-6087 3433);
FORCEPROP 2 LAST CDS_LIB mstr_standard
J 0
(-6025 3425);
DISPLAY 0.723404 (-6025 3425);
PAINT MONO (-6025 3425);
DISPLAY INVISIBLE (-6025 3425);
FORCEPROP 1 LAST BODY_TYPE PLUMBING
J 0
(-6025 3475);
DISPLAY 0.872340 (-6025 3475);
PAINT GREEN (-6025 3475);
DISPLAY INVISIBLE (-6025 3475);
FORCEPROP 1 LAST HDL_TAP TRUE
J 0
(-5700 3300);
DISPLAY 0.872340 (-5700 3300);
DISPLAY INVISIBLE (-5700 3300);
FORCEPROP 1 LAST PATH I62
J 0
(-6027 3425);
DISPLAY 0.872340 (-6027 3425);
PAINT GREEN (-6027 3425);
DISPLAY INVISIBLE (-6027 3425);
FORCEADD TAP..1
(-6025 3475);
FORCEPROP 3 LASTPIN (-6075 3475) SIG_NAME M_K_CPU0_SB_DQ<26>
J 0
(-6065 3485);
DISPLAY 0.659574 (-6065 3485);
PAINT MONO (-6065 3485);
DISPLAY INVISIBLE (-6065 3485);
FORCEPROP 1 LASTPIN (-6075 3475) BN 26
J 0
(-6087 3483);
DISPLAY 0.489362 (-6087 3483);
PAINT GREEN (-6087 3483);
FORCEPROP 2 LAST CDS_LIB mstr_standard
J 0
(-6025 3475);
DISPLAY 0.723404 (-6025 3475);
PAINT MONO (-6025 3475);
DISPLAY INVISIBLE (-6025 3475);
FORCEPROP 1 LAST BODY_TYPE PLUMBING
J 0
(-6025 3525);
DISPLAY 0.872340 (-6025 3525);
PAINT GREEN (-6025 3525);
DISPLAY INVISIBLE (-6025 3525);
FORCEPROP 1 LAST HDL_TAP TRUE
J 0
(-5700 3350);
DISPLAY 0.872340 (-5700 3350);
DISPLAY INVISIBLE (-5700 3350);
FORCEPROP 1 LAST PATH I63
J 0
(-6027 3475);
DISPLAY 0.872340 (-6027 3475);
PAINT GREEN (-6027 3475);
DISPLAY INVISIBLE (-6027 3475);
FORCEADD TAP..1
(-6025 3525);
FORCEPROP 3 LASTPIN (-6075 3525) SIG_NAME M_K_CPU0_SB_DQ<27>
J 0
(-6065 3535);
DISPLAY 0.659574 (-6065 3535);
PAINT MONO (-6065 3535);
DISPLAY INVISIBLE (-6065 3535);
FORCEPROP 1 LASTPIN (-6075 3525) BN 27
J 0
(-6087 3533);
DISPLAY 0.489362 (-6087 3533);
PAINT GREEN (-6087 3533);
FORCEPROP 2 LAST CDS_LIB mstr_standard
J 0
(-6025 3525);
DISPLAY 0.723404 (-6025 3525);
PAINT MONO (-6025 3525);
DISPLAY INVISIBLE (-6025 3525);
FORCEPROP 1 LAST BODY_TYPE PLUMBING
J 0
(-6025 3575);
DISPLAY 0.872340 (-6025 3575);
PAINT GREEN (-6025 3575);
DISPLAY INVISIBLE (-6025 3575);
FORCEPROP 1 LAST HDL_TAP TRUE
J 0
(-5700 3400);
DISPLAY 0.872340 (-5700 3400);
DISPLAY INVISIBLE (-5700 3400);
FORCEPROP 1 LAST PATH I64
J 0
(-6027 3525);
DISPLAY 0.872340 (-6027 3525);
PAINT GREEN (-6027 3525);
DISPLAY INVISIBLE (-6027 3525);
FORCEADD TAP..1
(-6025 3625);
FORCEPROP 3 LASTPIN (-6075 3625) SIG_NAME M_K_CPU0_SB_DQ<29>
J 0
(-6065 3635);
DISPLAY 0.659574 (-6065 3635);
PAINT MONO (-6065 3635);
DISPLAY INVISIBLE (-6065 3635);
FORCEPROP 1 LASTPIN (-6075 3625) BN 29
J 0
(-6087 3633);
DISPLAY 0.489362 (-6087 3633);
PAINT GREEN (-6087 3633);
FORCEPROP 2 LAST CDS_LIB mstr_standard
J 0
(-6025 3625);
DISPLAY 0.723404 (-6025 3625);
PAINT MONO (-6025 3625);
DISPLAY INVISIBLE (-6025 3625);
FORCEPROP 1 LAST BODY_TYPE PLUMBING
J 0
(-6025 3675);
DISPLAY 0.872340 (-6025 3675);
PAINT GREEN (-6025 3675);
DISPLAY INVISIBLE (-6025 3675);
FORCEPROP 1 LAST HDL_TAP TRUE
J 0
(-5700 3500);
DISPLAY 0.872340 (-5700 3500);
DISPLAY INVISIBLE (-5700 3500);
FORCEPROP 1 LAST PATH I65
J 0
(-6027 3625);
DISPLAY 0.872340 (-6027 3625);
PAINT GREEN (-6027 3625);
DISPLAY INVISIBLE (-6027 3625);
FORCEADD TAP..1
(-6025 3575);
FORCEPROP 3 LASTPIN (-6075 3575) SIG_NAME M_K_CPU0_SB_DQ<28>
J 0
(-6065 3585);
DISPLAY 0.659574 (-6065 3585);
PAINT MONO (-6065 3585);
DISPLAY INVISIBLE (-6065 3585);
FORCEPROP 1 LASTPIN (-6075 3575) BN 28
J 0
(-6087 3583);
DISPLAY 0.489362 (-6087 3583);
PAINT GREEN (-6087 3583);
FORCEPROP 2 LAST CDS_LIB mstr_standard
J 0
(-6025 3575);
DISPLAY 0.723404 (-6025 3575);
PAINT MONO (-6025 3575);
DISPLAY INVISIBLE (-6025 3575);
FORCEPROP 1 LAST BODY_TYPE PLUMBING
J 0
(-6025 3625);
DISPLAY 0.872340 (-6025 3625);
PAINT GREEN (-6025 3625);
DISPLAY INVISIBLE (-6025 3625);
FORCEPROP 1 LAST HDL_TAP TRUE
J 0
(-5700 3450);
DISPLAY 0.872340 (-5700 3450);
DISPLAY INVISIBLE (-5700 3450);
FORCEPROP 1 LAST PATH I66
J 0
(-6027 3575);
DISPLAY 0.872340 (-6027 3575);
PAINT GREEN (-6027 3575);
DISPLAY INVISIBLE (-6027 3575);
FORCEADD TAP..1
(-6025 3725);
FORCEPROP 3 LASTPIN (-6075 3725) SIG_NAME M_K_CPU0_SB_DQ<31>
J 0
(-6065 3735);
DISPLAY 0.659574 (-6065 3735);
PAINT MONO (-6065 3735);
DISPLAY INVISIBLE (-6065 3735);
FORCEPROP 1 LASTPIN (-6075 3725) BN 31
J 0
(-6087 3733);
DISPLAY 0.489362 (-6087 3733);
PAINT GREEN (-6087 3733);
FORCEPROP 2 LAST CDS_LIB mstr_standard
J 0
(-6025 3725);
DISPLAY 0.723404 (-6025 3725);
PAINT MONO (-6025 3725);
DISPLAY INVISIBLE (-6025 3725);
FORCEPROP 1 LAST BODY_TYPE PLUMBING
J 0
(-6025 3775);
DISPLAY 0.872340 (-6025 3775);
PAINT GREEN (-6025 3775);
DISPLAY INVISIBLE (-6025 3775);
FORCEPROP 1 LAST HDL_TAP TRUE
J 0
(-5700 3600);
DISPLAY 0.872340 (-5700 3600);
DISPLAY INVISIBLE (-5700 3600);
FORCEPROP 1 LAST PATH I67
J 0
(-6027 3725);
DISPLAY 0.872340 (-6027 3725);
PAINT GREEN (-6027 3725);
DISPLAY INVISIBLE (-6027 3725);
FORCEADD TAP..1
(-6025 3675);
FORCEPROP 3 LASTPIN (-6075 3675) SIG_NAME M_K_CPU0_SB_DQ<30>
J 0
(-6065 3685);
DISPLAY 0.659574 (-6065 3685);
PAINT MONO (-6065 3685);
DISPLAY INVISIBLE (-6065 3685);
FORCEPROP 1 LASTPIN (-6075 3675) BN 30
J 0
(-6087 3683);
DISPLAY 0.489362 (-6087 3683);
PAINT GREEN (-6087 3683);
FORCEPROP 2 LAST CDS_LIB mstr_standard
J 0
(-6025 3675);
DISPLAY 0.723404 (-6025 3675);
PAINT MONO (-6025 3675);
DISPLAY INVISIBLE (-6025 3675);
FORCEPROP 1 LAST BODY_TYPE PLUMBING
J 0
(-6025 3725);
DISPLAY 0.872340 (-6025 3725);
PAINT GREEN (-6025 3725);
DISPLAY INVISIBLE (-6025 3725);
FORCEPROP 1 LAST HDL_TAP TRUE
J 0
(-5700 3550);
DISPLAY 0.872340 (-5700 3550);
DISPLAY INVISIBLE (-5700 3550);
FORCEPROP 1 LAST PATH I68
J 0
(-6027 3675);
DISPLAY 0.872340 (-6027 3675);
PAINT GREEN (-6027 3675);
DISPLAY INVISIBLE (-6027 3675);
FORCEADD TAP..1
(-6025 3825);
FORCEPROP 3 LASTPIN (-6075 3825) SIG_NAME M_K_CPU0_SA_DQ<0>
J 0
(-6065 3835);
DISPLAY 0.659574 (-6065 3835);
PAINT MONO (-6065 3835);
DISPLAY INVISIBLE (-6065 3835);
FORCEPROP 1 LASTPIN (-6075 3825) BN 0
J 0
(-6087 3833);
DISPLAY 0.489362 (-6087 3833);
PAINT GREEN (-6087 3833);
FORCEPROP 2 LAST CDS_LIB mstr_standard
J 0
(-6025 3825);
DISPLAY 0.723404 (-6025 3825);
PAINT MONO (-6025 3825);
DISPLAY INVISIBLE (-6025 3825);
FORCEPROP 1 LAST BODY_TYPE PLUMBING
J 0
(-6025 3875);
DISPLAY 0.872340 (-6025 3875);
PAINT GREEN (-6025 3875);
DISPLAY INVISIBLE (-6025 3875);
FORCEPROP 1 LAST HDL_TAP TRUE
J 0
(-5700 3700);
DISPLAY 0.872340 (-5700 3700);
DISPLAY INVISIBLE (-5700 3700);
FORCEPROP 1 LAST PATH I69
J 0
(-6027 3825);
DISPLAY 0.872340 (-6027 3825);
PAINT GREEN (-6027 3825);
DISPLAY INVISIBLE (-6027 3825);
FORCEADD OFFPAGE..5
(-8150 3025);
FORCEPROP 2 LAST $XR0 20 
J 0
(-8374 3025);
DISPLAY 0.638298 (-8374 3025);
PAINT MONO (-8374 3025);
FORCEPROP 2 LAST PATH I7
J 0
(-8100 3100);
DISPLAY 1.021277 (-8100 3100);
DISPLAY INVISIBLE (-8100 3100);
FORCEPROP 1 LAST COMMENT_BODY TRUE
J 0
(-8050 2950);
DISPLAY 0.872340 (-8050 2950);
PAINT GREEN (-8050 2950);
DISPLAY INVISIBLE (-8050 2950);
FORCEPROP 1 LAST OFFPAGE TRUE
J 0
(-7825 2900);
DISPLAY 0.872340 (-7825 2900);
PAINT GREEN (-7825 2900);
DISPLAY INVISIBLE (-7825 2900);
FORCEPROP 2 LAST CDS_LIB mstr_standard
J 0
(-8150 3025);
DISPLAY INVISIBLE (-8150 3025);
FORCEADD TAP..1
(-6025 3875);
FORCEPROP 3 LASTPIN (-6075 3875) SIG_NAME M_K_CPU0_SA_DQ<1>
J 0
(-6065 3885);
DISPLAY 0.659574 (-6065 3885);
PAINT MONO (-6065 3885);
DISPLAY INVISIBLE (-6065 3885);
FORCEPROP 1 LASTPIN (-6075 3875) BN 1
J 0
(-6087 3883);
DISPLAY 0.489362 (-6087 3883);
PAINT GREEN (-6087 3883);
FORCEPROP 2 LAST CDS_LIB mstr_standard
J 0
(-6025 3875);
DISPLAY 0.723404 (-6025 3875);
PAINT MONO (-6025 3875);
DISPLAY INVISIBLE (-6025 3875);
FORCEPROP 1 LAST BODY_TYPE PLUMBING
J 0
(-6025 3925);
DISPLAY 0.872340 (-6025 3925);
PAINT GREEN (-6025 3925);
DISPLAY INVISIBLE (-6025 3925);
FORCEPROP 1 LAST HDL_TAP TRUE
J 0
(-5700 3750);
DISPLAY 0.872340 (-5700 3750);
DISPLAY INVISIBLE (-5700 3750);
FORCEPROP 1 LAST PATH I70
J 0
(-6027 3875);
DISPLAY 0.872340 (-6027 3875);
PAINT GREEN (-6027 3875);
DISPLAY INVISIBLE (-6027 3875);
FORCEADD OFFPAGE..3
(-5350 3775);
FORCEPROP 2 LAST $XR0 20 
J 0
(-5136 3775);
DISPLAY 0.638298 (-5136 3775);
PAINT MONO (-5136 3775);
FORCEPROP 2 LAST PATH I78
J 0
(-5150 3850);
DISPLAY 1.021277 (-5150 3850);
DISPLAY INVISIBLE (-5150 3850);
FORCEPROP 1 LAST COMMENT_BODY TRUE
J 0
(-5400 3675);
DISPLAY 0.872340 (-5400 3675);
PAINT GREEN (-5400 3675);
DISPLAY INVISIBLE (-5400 3675);
FORCEPROP 1 LAST OFFPAGE TRUE
J 0
(-5025 3650);
DISPLAY 0.872340 (-5025 3650);
PAINT GREEN (-5025 3650);
DISPLAY INVISIBLE (-5025 3650);
FORCEPROP 2 LAST CDS_LIB mstr_standard
J 0
(-5350 3775);
DISPLAY 0.723404 (-5350 3775);
PAINT MONO (-5350 3775);
DISPLAY INVISIBLE (-5350 3775);
FORCEADD OFFPAGE..1
(-8150 3075);
FORCEPROP 2 LAST $XR0 20 
J 0
(-8401 3075);
DISPLAY 0.638298 (-8401 3075);
PAINT MONO (-8401 3075);
FORCEPROP 2 LAST PATH I8
J 0
(-8575 3125);
DISPLAY 1.021277 (-8575 3125);
DISPLAY INVISIBLE (-8575 3125);
FORCEPROP 1 LAST COMMENT_BODY TRUE
J 0
(-8025 2975);
DISPLAY 0.872340 (-8025 2975);
PAINT GREEN (-8025 2975);
DISPLAY INVISIBLE (-8025 2975);
FORCEPROP 1 LAST OFFPAGE TRUE
J 0
(-7825 2950);
DISPLAY 0.872340 (-7825 2950);
PAINT GREEN (-7825 2950);
DISPLAY INVISIBLE (-7825 2950);
FORCEPROP 2 LAST CDS_LIB mstr_standard
J 0
(-8150 3075);
DISPLAY 0.808511 (-8150 3075);
DISPLAY INVISIBLE (-8150 3075);
FORCEADD TAP..1
R 2
(-7725 3925);
FORCEPROP 3 LASTPIN (-7675 3925) SIG_NAME M_K_CPU0_SA_CB<6>
J 0
(-7665 3935);
DISPLAY 0.659574 (-7665 3935);
PAINT MONO (-7665 3935);
DISPLAY INVISIBLE (-7665 3935);
FORCEPROP 1 LASTPIN (-7675 3925) BN 6
J 2
(-7663 3933);
DISPLAY 0.489362 (-7663 3933);
PAINT GREEN (-7663 3933);
FORCEPROP 2 LAST CDS_LIB mstr_standard
J 0
(-7725 3925);
DISPLAY 0.723404 (-7725 3925);
PAINT MONO (-7725 3925);
DISPLAY INVISIBLE (-7725 3925);
FORCEPROP 1 LAST BODY_TYPE PLUMBING
J 2
(-7725 3975);
DISPLAY 0.872340 (-7725 3975);
PAINT GREEN (-7725 3975);
DISPLAY INVISIBLE (-7725 3975);
FORCEPROP 1 LAST HDL_TAP TRUE
J 2
(-8050 3800);
DISPLAY 0.872340 (-8050 3800);
DISPLAY INVISIBLE (-8050 3800);
FORCEPROP 1 LAST PATH I80
J 2
(-7723 3925);
DISPLAY 0.872340 (-7723 3925);
PAINT GREEN (-7723 3925);
DISPLAY INVISIBLE (-7723 3925);
FORCEADD TAP..1
R 2
(-7725 3975);
FORCEPROP 3 LASTPIN (-7675 3975) SIG_NAME M_K_CPU0_SA_CB<7>
J 0
(-7665 3985);
DISPLAY 0.659574 (-7665 3985);
PAINT MONO (-7665 3985);
DISPLAY INVISIBLE (-7665 3985);
FORCEPROP 1 LASTPIN (-7675 3975) BN 7
J 2
(-7663 3983);
DISPLAY 0.489362 (-7663 3983);
PAINT GREEN (-7663 3983);
FORCEPROP 2 LAST CDS_LIB mstr_standard
J 0
(-7725 3975);
DISPLAY 0.723404 (-7725 3975);
PAINT MONO (-7725 3975);
DISPLAY INVISIBLE (-7725 3975);
FORCEPROP 1 LAST BODY_TYPE PLUMBING
J 2
(-7725 4025);
DISPLAY 0.872340 (-7725 4025);
PAINT GREEN (-7725 4025);
DISPLAY INVISIBLE (-7725 4025);
FORCEPROP 1 LAST HDL_TAP TRUE
J 2
(-8050 3850);
DISPLAY 0.872340 (-8050 3850);
DISPLAY INVISIBLE (-8050 3850);
FORCEPROP 1 LAST PATH I81
J 2
(-7723 3975);
DISPLAY 0.872340 (-7723 3975);
PAINT GREEN (-7723 3975);
DISPLAY INVISIBLE (-7723 3975);
FORCEADD TAP..1
R 2
(-7725 4675);
FORCEPROP 3 LASTPIN (-7675 4675) SIG_NAME M_K_CPU0_SB_CA<0>
J 0
(-7665 4685);
DISPLAY 0.659574 (-7665 4685);
PAINT MONO (-7665 4685);
DISPLAY INVISIBLE (-7665 4685);
FORCEPROP 1 LASTPIN (-7675 4675) BN 0
J 2
(-7663 4683);
DISPLAY 0.489362 (-7663 4683);
PAINT GREEN (-7663 4683);
FORCEPROP 2 LAST CDS_LIB mstr_standard
J 0
(-7725 4675);
DISPLAY 0.723404 (-7725 4675);
PAINT MONO (-7725 4675);
DISPLAY INVISIBLE (-7725 4675);
FORCEPROP 1 LAST BODY_TYPE PLUMBING
J 2
(-7725 4725);
DISPLAY 0.872340 (-7725 4725);
PAINT GREEN (-7725 4725);
DISPLAY INVISIBLE (-7725 4725);
FORCEPROP 1 LAST HDL_TAP TRUE
J 2
(-8050 4550);
DISPLAY 0.872340 (-8050 4550);
DISPLAY INVISIBLE (-8050 4550);
FORCEPROP 1 LAST PATH I82
J 2
(-7723 4675);
DISPLAY 0.872340 (-7723 4675);
PAINT GREEN (-7723 4675);
DISPLAY INVISIBLE (-7723 4675);
FORCEADD TAP..1
R 2
(-7725 4775);
FORCEPROP 3 LASTPIN (-7675 4775) SIG_NAME M_K_CPU0_SB_CA<2>
J 0
(-7665 4785);
DISPLAY 0.659574 (-7665 4785);
PAINT MONO (-7665 4785);
DISPLAY INVISIBLE (-7665 4785);
FORCEPROP 1 LASTPIN (-7675 4775) BN 2
J 2
(-7663 4783);
DISPLAY 0.489362 (-7663 4783);
PAINT GREEN (-7663 4783);
FORCEPROP 2 LAST CDS_LIB mstr_standard
J 0
(-7725 4775);
DISPLAY 0.723404 (-7725 4775);
PAINT MONO (-7725 4775);
DISPLAY INVISIBLE (-7725 4775);
FORCEPROP 1 LAST BODY_TYPE PLUMBING
J 2
(-7725 4825);
DISPLAY 0.872340 (-7725 4825);
PAINT GREEN (-7725 4825);
DISPLAY INVISIBLE (-7725 4825);
FORCEPROP 1 LAST HDL_TAP TRUE
J 2
(-8050 4650);
DISPLAY 0.872340 (-8050 4650);
DISPLAY INVISIBLE (-8050 4650);
FORCEPROP 1 LAST PATH I83
J 2
(-7723 4775);
DISPLAY 0.872340 (-7723 4775);
PAINT GREEN (-7723 4775);
DISPLAY INVISIBLE (-7723 4775);
FORCEADD TAP..1
R 2
(-7725 4725);
FORCEPROP 3 LASTPIN (-7675 4725) SIG_NAME M_K_CPU0_SB_CA<1>
J 0
(-7665 4735);
DISPLAY 0.659574 (-7665 4735);
PAINT MONO (-7665 4735);
DISPLAY INVISIBLE (-7665 4735);
FORCEPROP 1 LASTPIN (-7675 4725) BN 1
J 2
(-7663 4733);
DISPLAY 0.489362 (-7663 4733);
PAINT GREEN (-7663 4733);
FORCEPROP 2 LAST CDS_LIB mstr_standard
J 0
(-7725 4725);
DISPLAY 0.723404 (-7725 4725);
PAINT MONO (-7725 4725);
DISPLAY INVISIBLE (-7725 4725);
FORCEPROP 1 LAST BODY_TYPE PLUMBING
J 2
(-7725 4775);
DISPLAY 0.872340 (-7725 4775);
PAINT GREEN (-7725 4775);
DISPLAY INVISIBLE (-7725 4775);
FORCEPROP 1 LAST HDL_TAP TRUE
J 2
(-8050 4600);
DISPLAY 0.872340 (-8050 4600);
DISPLAY INVISIBLE (-8050 4600);
FORCEPROP 1 LAST PATH I84
J 2
(-7723 4725);
DISPLAY 0.872340 (-7723 4725);
PAINT GREEN (-7723 4725);
DISPLAY INVISIBLE (-7723 4725);
FORCEADD TAP..1
R 2
(-7725 4875);
FORCEPROP 3 LASTPIN (-7675 4875) SIG_NAME M_K_CPU0_SB_CA<4>
J 0
(-7665 4885);
DISPLAY 0.659574 (-7665 4885);
PAINT MONO (-7665 4885);
DISPLAY INVISIBLE (-7665 4885);
FORCEPROP 1 LASTPIN (-7675 4875) BN 4
J 2
(-7663 4883);
DISPLAY 0.489362 (-7663 4883);
PAINT GREEN (-7663 4883);
FORCEPROP 2 LAST CDS_LIB mstr_standard
J 0
(-7725 4875);
DISPLAY 0.723404 (-7725 4875);
PAINT MONO (-7725 4875);
DISPLAY INVISIBLE (-7725 4875);
FORCEPROP 1 LAST BODY_TYPE PLUMBING
J 2
(-7725 4925);
DISPLAY 0.872340 (-7725 4925);
PAINT GREEN (-7725 4925);
DISPLAY INVISIBLE (-7725 4925);
FORCEPROP 1 LAST HDL_TAP TRUE
J 2
(-8050 4750);
DISPLAY 0.872340 (-8050 4750);
DISPLAY INVISIBLE (-8050 4750);
FORCEPROP 1 LAST PATH I85
J 2
(-7723 4875);
DISPLAY 0.872340 (-7723 4875);
PAINT GREEN (-7723 4875);
DISPLAY INVISIBLE (-7723 4875);
FORCEADD TAP..1
R 2
(-7725 4825);
FORCEPROP 3 LASTPIN (-7675 4825) SIG_NAME M_K_CPU0_SB_CA<3>
J 0
(-7665 4835);
DISPLAY 0.659574 (-7665 4835);
PAINT MONO (-7665 4835);
DISPLAY INVISIBLE (-7665 4835);
FORCEPROP 1 LASTPIN (-7675 4825) BN 3
J 2
(-7663 4833);
DISPLAY 0.489362 (-7663 4833);
PAINT GREEN (-7663 4833);
FORCEPROP 2 LAST CDS_LIB mstr_standard
J 0
(-7725 4825);
DISPLAY 0.723404 (-7725 4825);
PAINT MONO (-7725 4825);
DISPLAY INVISIBLE (-7725 4825);
FORCEPROP 1 LAST BODY_TYPE PLUMBING
J 2
(-7725 4875);
DISPLAY 0.872340 (-7725 4875);
PAINT GREEN (-7725 4875);
DISPLAY INVISIBLE (-7725 4875);
FORCEPROP 1 LAST HDL_TAP TRUE
J 2
(-8050 4700);
DISPLAY 0.872340 (-8050 4700);
DISPLAY INVISIBLE (-8050 4700);
FORCEPROP 1 LAST PATH I86
J 2
(-7723 4825);
DISPLAY 0.872340 (-7723 4825);
PAINT GREEN (-7723 4825);
DISPLAY INVISIBLE (-7723 4825);
FORCEADD TAP..1
R 2
(-7725 4925);
FORCEPROP 3 LASTPIN (-7675 4925) SIG_NAME M_K_CPU0_SB_CA<5>
J 0
(-7665 4935);
DISPLAY 0.659574 (-7665 4935);
PAINT MONO (-7665 4935);
DISPLAY INVISIBLE (-7665 4935);
FORCEPROP 1 LASTPIN (-7675 4925) BN 5
J 2
(-7663 4933);
DISPLAY 0.489362 (-7663 4933);
PAINT GREEN (-7663 4933);
FORCEPROP 2 LAST CDS_LIB mstr_standard
J 0
(-7725 4925);
DISPLAY 0.723404 (-7725 4925);
PAINT MONO (-7725 4925);
DISPLAY INVISIBLE (-7725 4925);
FORCEPROP 1 LAST BODY_TYPE PLUMBING
J 2
(-7725 4975);
DISPLAY 0.872340 (-7725 4975);
PAINT GREEN (-7725 4975);
DISPLAY INVISIBLE (-7725 4975);
FORCEPROP 1 LAST HDL_TAP TRUE
J 2
(-8050 4800);
DISPLAY 0.872340 (-8050 4800);
DISPLAY INVISIBLE (-8050 4800);
FORCEPROP 1 LAST PATH I87
J 2
(-7723 4925);
DISPLAY 0.872340 (-7723 4925);
PAINT GREEN (-7723 4925);
DISPLAY INVISIBLE (-7723 4925);
FORCEADD TAP..1
R 2
(-7725 4975);
FORCEPROP 3 LASTPIN (-7675 4975) SIG_NAME M_K_CPU0_SB_CA<6>
J 0
(-7665 4985);
DISPLAY 0.659574 (-7665 4985);
PAINT MONO (-7665 4985);
DISPLAY INVISIBLE (-7665 4985);
FORCEPROP 1 LASTPIN (-7675 4975) BN 6
J 2
(-7663 4983);
DISPLAY 0.489362 (-7663 4983);
PAINT GREEN (-7663 4983);
FORCEPROP 2 LAST CDS_LIB mstr_standard
J 0
(-7725 4975);
DISPLAY 0.723404 (-7725 4975);
PAINT MONO (-7725 4975);
DISPLAY INVISIBLE (-7725 4975);
FORCEPROP 1 LAST BODY_TYPE PLUMBING
J 2
(-7725 5025);
DISPLAY 0.872340 (-7725 5025);
PAINT GREEN (-7725 5025);
DISPLAY INVISIBLE (-7725 5025);
FORCEPROP 1 LAST HDL_TAP TRUE
J 2
(-8050 4850);
DISPLAY 0.872340 (-8050 4850);
DISPLAY INVISIBLE (-8050 4850);
FORCEPROP 1 LAST PATH I88
J 2
(-7723 4975);
DISPLAY 0.872340 (-7723 4975);
PAINT GREEN (-7723 4975);
DISPLAY INVISIBLE (-7723 4975);
FORCEADD TAP..1
R 2
(-7725 5075);
FORCEPROP 3 LASTPIN (-7675 5075) SIG_NAME M_K_CPU0_SA_CA<0>
J 0
(-7665 5085);
DISPLAY 0.659574 (-7665 5085);
PAINT MONO (-7665 5085);
DISPLAY INVISIBLE (-7665 5085);
FORCEPROP 1 LASTPIN (-7675 5075) BN 0
J 2
(-7663 5083);
DISPLAY 0.489362 (-7663 5083);
PAINT GREEN (-7663 5083);
FORCEPROP 2 LAST CDS_LIB mstr_standard
J 0
(-7725 5075);
DISPLAY 0.723404 (-7725 5075);
PAINT MONO (-7725 5075);
DISPLAY INVISIBLE (-7725 5075);
FORCEPROP 1 LAST BODY_TYPE PLUMBING
J 2
(-7725 5125);
DISPLAY 0.872340 (-7725 5125);
PAINT GREEN (-7725 5125);
DISPLAY INVISIBLE (-7725 5125);
FORCEPROP 1 LAST HDL_TAP TRUE
J 2
(-8050 4950);
DISPLAY 0.872340 (-8050 4950);
DISPLAY INVISIBLE (-8050 4950);
FORCEPROP 1 LAST PATH I89
J 2
(-7723 5075);
DISPLAY 0.872340 (-7723 5075);
PAINT GREEN (-7723 5075);
DISPLAY INVISIBLE (-7723 5075);
FORCEADD VCC_CORE..1
(-8500 3400);
FORCEPROP 3 LASTPIN (-8500 3350) SIG_NAME P3V3_STBY\g
J 0
(-8490 3360);
DISPLAY 0.659574 (-8490 3360);
PAINT MONO (-8490 3360);
DISPLAY INVISIBLE (-8490 3360);
FORCEPROP 1 LAST HDL_POWER P3V3_STBY
J 1
(-8500 3450);
DISPLAY 0.489362 (-8500 3450);
PAINT GREEN (-8500 3450);
FORCEPROP 2 LAST CDS_LIB mstr_symbols
J 0
(-8500 3400);
PAINT MONO (-8500 3400);
DISPLAY INVISIBLE (-8500 3400);
FORCEPROP 1 LAST PATH I9
J 0
(-8450 3425);
DISPLAY 0.872340 (-8450 3425);
PAINT AQUA (-8450 3425);
DISPLAY INVISIBLE (-8450 3425);
FORCEPROP 0 LAST VOLTAGE 3.3
J 0
(-8775 3550);
DISPLAY 1.021277 (-8775 3550);
PAINT SKYBLUE (-8775 3550);
DISPLAY INVISIBLE (-8775 3550);
FORCEPROP 2 LAST ROOM PVCCINFAON_CPU0_CTRL
J 0
(-8500 3500);
DISPLAY 0.808511 (-8500 3500);
PAINT RED (-8500 3500);
DISPLAY INVISIBLE (-8500 3500);
FORCEADD TAP..1
R 2
(-7725 5125);
FORCEPROP 3 LASTPIN (-7675 5125) SIG_NAME M_K_CPU0_SA_CA<1>
J 0
(-7665 5135);
DISPLAY 0.659574 (-7665 5135);
PAINT MONO (-7665 5135);
DISPLAY INVISIBLE (-7665 5135);
FORCEPROP 1 LASTPIN (-7675 5125) BN 1
J 2
(-7663 5133);
DISPLAY 0.489362 (-7663 5133);
PAINT GREEN (-7663 5133);
FORCEPROP 2 LAST CDS_LIB mstr_standard
J 0
(-7725 5125);
DISPLAY 0.723404 (-7725 5125);
PAINT MONO (-7725 5125);
DISPLAY INVISIBLE (-7725 5125);
FORCEPROP 1 LAST BODY_TYPE PLUMBING
J 2
(-7725 5175);
DISPLAY 0.872340 (-7725 5175);
PAINT GREEN (-7725 5175);
DISPLAY INVISIBLE (-7725 5175);
FORCEPROP 1 LAST HDL_TAP TRUE
J 2
(-8050 5000);
DISPLAY 0.872340 (-8050 5000);
DISPLAY INVISIBLE (-8050 5000);
FORCEPROP 1 LAST PATH I90
J 2
(-7723 5125);
DISPLAY 0.872340 (-7723 5125);
PAINT GREEN (-7723 5125);
DISPLAY INVISIBLE (-7723 5125);
FORCEADD TAP..1
R 2
(-7725 5175);
FORCEPROP 3 LASTPIN (-7675 5175) SIG_NAME M_K_CPU0_SA_CA<2>
J 0
(-7665 5185);
DISPLAY 0.659574 (-7665 5185);
PAINT MONO (-7665 5185);
DISPLAY INVISIBLE (-7665 5185);
FORCEPROP 1 LASTPIN (-7675 5175) BN 2
J 2
(-7663 5183);
DISPLAY 0.489362 (-7663 5183);
PAINT GREEN (-7663 5183);
FORCEPROP 2 LAST CDS_LIB mstr_standard
J 0
(-7725 5175);
DISPLAY 0.723404 (-7725 5175);
PAINT MONO (-7725 5175);
DISPLAY INVISIBLE (-7725 5175);
FORCEPROP 1 LAST BODY_TYPE PLUMBING
J 2
(-7725 5225);
DISPLAY 0.872340 (-7725 5225);
PAINT GREEN (-7725 5225);
DISPLAY INVISIBLE (-7725 5225);
FORCEPROP 1 LAST HDL_TAP TRUE
J 2
(-8050 5050);
DISPLAY 0.872340 (-8050 5050);
DISPLAY INVISIBLE (-8050 5050);
FORCEPROP 1 LAST PATH I91
J 2
(-7723 5175);
DISPLAY 0.872340 (-7723 5175);
PAINT GREEN (-7723 5175);
DISPLAY INVISIBLE (-7723 5175);
FORCEADD TAP..1
R 2
(-7725 5225);
FORCEPROP 3 LASTPIN (-7675 5225) SIG_NAME M_K_CPU0_SA_CA<3>
J 0
(-7665 5235);
DISPLAY 0.659574 (-7665 5235);
PAINT MONO (-7665 5235);
DISPLAY INVISIBLE (-7665 5235);
FORCEPROP 1 LASTPIN (-7675 5225) BN 3
J 2
(-7663 5233);
DISPLAY 0.489362 (-7663 5233);
PAINT GREEN (-7663 5233);
FORCEPROP 2 LAST CDS_LIB mstr_standard
J 0
(-7725 5225);
DISPLAY 0.723404 (-7725 5225);
PAINT MONO (-7725 5225);
DISPLAY INVISIBLE (-7725 5225);
FORCEPROP 1 LAST BODY_TYPE PLUMBING
J 2
(-7725 5275);
DISPLAY 0.872340 (-7725 5275);
PAINT GREEN (-7725 5275);
DISPLAY INVISIBLE (-7725 5275);
FORCEPROP 1 LAST HDL_TAP TRUE
J 2
(-8050 5100);
DISPLAY 0.872340 (-8050 5100);
DISPLAY INVISIBLE (-8050 5100);
FORCEPROP 1 LAST PATH I92
J 2
(-7723 5225);
DISPLAY 0.872340 (-7723 5225);
PAINT GREEN (-7723 5225);
DISPLAY INVISIBLE (-7723 5225);
FORCEADD TAP..1
R 2
(-7725 5275);
FORCEPROP 3 LASTPIN (-7675 5275) SIG_NAME M_K_CPU0_SA_CA<4>
J 0
(-7665 5285);
DISPLAY 0.659574 (-7665 5285);
PAINT MONO (-7665 5285);
DISPLAY INVISIBLE (-7665 5285);
FORCEPROP 1 LASTPIN (-7675 5275) BN 4
J 2
(-7663 5283);
DISPLAY 0.489362 (-7663 5283);
PAINT GREEN (-7663 5283);
FORCEPROP 2 LAST CDS_LIB mstr_standard
J 0
(-7725 5275);
DISPLAY 0.723404 (-7725 5275);
PAINT MONO (-7725 5275);
DISPLAY INVISIBLE (-7725 5275);
FORCEPROP 1 LAST BODY_TYPE PLUMBING
J 2
(-7725 5325);
DISPLAY 0.872340 (-7725 5325);
PAINT GREEN (-7725 5325);
DISPLAY INVISIBLE (-7725 5325);
FORCEPROP 1 LAST HDL_TAP TRUE
J 2
(-8050 5150);
DISPLAY 0.872340 (-8050 5150);
DISPLAY INVISIBLE (-8050 5150);
FORCEPROP 1 LAST PATH I93
J 2
(-7723 5275);
DISPLAY 0.872340 (-7723 5275);
PAINT GREEN (-7723 5275);
DISPLAY INVISIBLE (-7723 5275);
FORCEADD TAP..1
R 2
(-7725 5325);
FORCEPROP 3 LASTPIN (-7675 5325) SIG_NAME M_K_CPU0_SA_CA<5>
J 0
(-7665 5335);
DISPLAY 0.659574 (-7665 5335);
PAINT MONO (-7665 5335);
DISPLAY INVISIBLE (-7665 5335);
FORCEPROP 1 LASTPIN (-7675 5325) BN 5
J 2
(-7663 5333);
DISPLAY 0.489362 (-7663 5333);
PAINT GREEN (-7663 5333);
FORCEPROP 2 LAST CDS_LIB mstr_standard
J 0
(-7725 5325);
DISPLAY 0.723404 (-7725 5325);
PAINT MONO (-7725 5325);
DISPLAY INVISIBLE (-7725 5325);
FORCEPROP 1 LAST BODY_TYPE PLUMBING
J 2
(-7725 5375);
DISPLAY 0.872340 (-7725 5375);
PAINT GREEN (-7725 5375);
DISPLAY INVISIBLE (-7725 5375);
FORCEPROP 1 LAST HDL_TAP TRUE
J 2
(-8050 5200);
DISPLAY 0.872340 (-8050 5200);
DISPLAY INVISIBLE (-8050 5200);
FORCEPROP 1 LAST PATH I94
J 2
(-7723 5325);
DISPLAY 0.872340 (-7723 5325);
PAINT GREEN (-7723 5325);
DISPLAY INVISIBLE (-7723 5325);
FORCEADD TAP..1
R 2
(-7725 5375);
FORCEPROP 3 LASTPIN (-7675 5375) SIG_NAME M_K_CPU0_SA_CA<6>
J 0
(-7665 5385);
DISPLAY 0.659574 (-7665 5385);
PAINT MONO (-7665 5385);
DISPLAY INVISIBLE (-7665 5385);
FORCEPROP 1 LASTPIN (-7675 5375) BN 6
J 2
(-7663 5383);
DISPLAY 0.489362 (-7663 5383);
PAINT GREEN (-7663 5383);
FORCEPROP 2 LAST CDS_LIB mstr_standard
J 0
(-7725 5375);
DISPLAY 0.723404 (-7725 5375);
PAINT MONO (-7725 5375);
DISPLAY INVISIBLE (-7725 5375);
FORCEPROP 1 LAST BODY_TYPE PLUMBING
J 2
(-7725 5425);
DISPLAY 0.872340 (-7725 5425);
PAINT GREEN (-7725 5425);
DISPLAY INVISIBLE (-7725 5425);
FORCEPROP 1 LAST HDL_TAP TRUE
J 2
(-8050 5250);
DISPLAY 0.872340 (-8050 5250);
DISPLAY INVISIBLE (-8050 5250);
FORCEPROP 1 LAST PATH I95
J 2
(-7723 5375);
DISPLAY 0.872340 (-7723 5375);
PAINT GREEN (-7723 5375);
DISPLAY INVISIBLE (-7723 5375);
FORCEADD TAP..1
(-6025 3925);
FORCEPROP 3 LASTPIN (-6075 3925) SIG_NAME M_K_CPU0_SA_DQ<2>
J 0
(-6065 3935);
DISPLAY 0.659574 (-6065 3935);
PAINT MONO (-6065 3935);
DISPLAY INVISIBLE (-6065 3935);
FORCEPROP 1 LASTPIN (-6075 3925) BN 2
J 0
(-6087 3933);
DISPLAY 0.489362 (-6087 3933);
PAINT GREEN (-6087 3933);
FORCEPROP 2 LAST CDS_LIB mstr_standard
J 0
(-6025 3925);
DISPLAY 0.723404 (-6025 3925);
PAINT MONO (-6025 3925);
DISPLAY INVISIBLE (-6025 3925);
FORCEPROP 1 LAST BODY_TYPE PLUMBING
J 0
(-6025 3975);
DISPLAY 0.872340 (-6025 3975);
PAINT GREEN (-6025 3975);
DISPLAY INVISIBLE (-6025 3975);
FORCEPROP 1 LAST HDL_TAP TRUE
J 0
(-5700 3800);
DISPLAY 0.872340 (-5700 3800);
DISPLAY INVISIBLE (-5700 3800);
FORCEPROP 1 LAST PATH I96
J 0
(-6027 3925);
DISPLAY 0.872340 (-6027 3925);
PAINT GREEN (-6027 3925);
DISPLAY INVISIBLE (-6027 3925);
FORCEADD TAP..1
(-6025 3975);
FORCEPROP 3 LASTPIN (-6075 3975) SIG_NAME M_K_CPU0_SA_DQ<3>
J 0
(-6065 3985);
DISPLAY 0.659574 (-6065 3985);
PAINT MONO (-6065 3985);
DISPLAY INVISIBLE (-6065 3985);
FORCEPROP 1 LASTPIN (-6075 3975) BN 3
J 0
(-6087 3983);
DISPLAY 0.489362 (-6087 3983);
PAINT GREEN (-6087 3983);
FORCEPROP 2 LAST CDS_LIB mstr_standard
J 0
(-6025 3975);
DISPLAY 0.723404 (-6025 3975);
PAINT MONO (-6025 3975);
DISPLAY INVISIBLE (-6025 3975);
FORCEPROP 1 LAST BODY_TYPE PLUMBING
J 0
(-6025 4025);
DISPLAY 0.872340 (-6025 4025);
PAINT GREEN (-6025 4025);
DISPLAY INVISIBLE (-6025 4025);
FORCEPROP 1 LAST HDL_TAP TRUE
J 0
(-5700 3850);
DISPLAY 0.872340 (-5700 3850);
DISPLAY INVISIBLE (-5700 3850);
FORCEPROP 1 LAST PATH I97
J 0
(-6027 3975);
DISPLAY 0.872340 (-6027 3975);
PAINT GREEN (-6027 3975);
DISPLAY INVISIBLE (-6027 3975);
FORCEADD TAP..1
(-6025 4025);
FORCEPROP 3 LASTPIN (-6075 4025) SIG_NAME M_K_CPU0_SA_DQ<4>
J 0
(-6065 4035);
DISPLAY 0.659574 (-6065 4035);
PAINT MONO (-6065 4035);
DISPLAY INVISIBLE (-6065 4035);
FORCEPROP 1 LASTPIN (-6075 4025) BN 4
J 0
(-6087 4033);
DISPLAY 0.489362 (-6087 4033);
PAINT GREEN (-6087 4033);
FORCEPROP 2 LAST CDS_LIB mstr_standard
J 0
(-6025 4025);
DISPLAY 0.723404 (-6025 4025);
PAINT MONO (-6025 4025);
DISPLAY INVISIBLE (-6025 4025);
FORCEPROP 1 LAST BODY_TYPE PLUMBING
J 0
(-6025 4075);
DISPLAY 0.872340 (-6025 4075);
PAINT GREEN (-6025 4075);
DISPLAY INVISIBLE (-6025 4075);
FORCEPROP 1 LAST HDL_TAP TRUE
J 0
(-5700 3900);
DISPLAY 0.872340 (-5700 3900);
DISPLAY INVISIBLE (-5700 3900);
FORCEPROP 1 LAST PATH I98
J 0
(-6027 4025);
DISPLAY 0.872340 (-6027 4025);
PAINT GREEN (-6027 4025);
DISPLAY INVISIBLE (-6027 4025);
FORCEADD TAP..1
(-6025 4075);
FORCEPROP 3 LASTPIN (-6075 4075) SIG_NAME M_K_CPU0_SA_DQ<5>
J 0
(-6065 4085);
DISPLAY 0.659574 (-6065 4085);
PAINT MONO (-6065 4085);
DISPLAY INVISIBLE (-6065 4085);
FORCEPROP 1 LASTPIN (-6075 4075) BN 5
J 0
(-6087 4083);
DISPLAY 0.489362 (-6087 4083);
PAINT GREEN (-6087 4083);
FORCEPROP 2 LAST CDS_LIB mstr_standard
J 0
(-6025 4075);
DISPLAY 0.723404 (-6025 4075);
PAINT MONO (-6025 4075);
DISPLAY INVISIBLE (-6025 4075);
FORCEPROP 1 LAST BODY_TYPE PLUMBING
J 0
(-6025 4125);
DISPLAY 0.872340 (-6025 4125);
PAINT GREEN (-6025 4125);
DISPLAY INVISIBLE (-6025 4125);
FORCEPROP 1 LAST HDL_TAP TRUE
J 0
(-5700 3950);
DISPLAY 0.872340 (-5700 3950);
DISPLAY INVISIBLE (-5700 3950);
FORCEPROP 1 LAST PATH I99
J 0
(-6027 4075);
DISPLAY 0.872340 (-6027 4075);
PAINT GREEN (-6027 4075);
DISPLAY INVISIBLE (-6027 4075);
FORCEADD QUANTA_TITLE_BLOCK_C..1
(0 0);
FORCEPROP 0 LAST CDS_CON_LAST_MODIFIED Fri Mar 11 14:52:59 2022
J 0
(-1885 15);
DISPLAY INVISIBLE (-1885 15);
FORCEPROP 1 LAST CUSTOM_TXT_CDS <CON_LAST_MODIFIED>
J 0
(-1885 15);
DISPLAY 0.978723 (-1885 15);
FORCEPROP 2 LAST CUSTOM_TXT_CDS <XR_PAGE_TITLE>
J 0
(-7890 5250);
DISPLAY 0.638298 (-7890 5250);
PAINT PINK (-7890 5250);
DISPLAY INVISIBLE (-7890 5250);
FORCEPROP 1 LAST CUSTOM_TXT_CDS <NAME_2>
J 0
(-3175 50);
FORCEPROP 1 LAST CUSTOM_TXT_CDS <NAME_1>
J 0
(-3175 175);
FORCEPROP 1 LAST CUSTOM_TXT_CDS <Q_NUMBER>
J 0
(-1403 103);
DISPLAY 1.212766 (-1403 103);
FORCEPROP 1 LAST CUSTOM_TXT_CDS <Q_PROJ>
J 0
(-2382 102);
DISPLAY 1.212766 (-2382 102);
FORCEPROP 1 LAST CUSTOM_TXT_CDS <Q_REV>
J 0
(-184 103);
DISPLAY 1.212766 (-184 103);
FORCEPROP 1 LAST CUSTOM_TXT_CDS <CON_PAGE_NUM> OF <CON_TOTAL_PAGES>
J 0
(-446 18);
DISPLAY 0.978723 (-446 18);
FORCEPROP 1 LAST Q_TITLE DDR5 - CPU0 CHK
J 0
(-9366 26);
DISPLAY 2.446809 (-9366 26);
PAINT GREEN (-9366 26);
FORCEPROP 1 LAST Q_DEPT BU9
J 1
(-3763 49);
DISPLAY 1.957447 (-3763 49);
PAINT GREEN (-3763 49);
FORCEPROP 2 LAST PAGE_BORDER TRUE
J 0
(-7890 5250);
DISPLAY 0.638298 (-7890 5250);
PAINT PINK (-7890 5250);
DISPLAY INVISIBLE (-7890 5250);
FORCEPROP 1 LAST CDS_LMAN_SYM_OUTLINE -9475,6775,100,-125
J 0
(0 0);
DISPLAY 0.468085 (0 0);
PAINT GREEN (0 0);
DISPLAY INVISIBLE (0 0);
FORCEPROP 2 LAST CDS_LIB pure_quanta
J 0
(0 0);
DISPLAY INVISIBLE (0 0);
FORCEPROP 1 LAST COMMENT_BODY TRUE
J 0
(12 -13);
DISPLAY 0.978723 (12 -13);
PAINT GREEN (12 -13);
DISPLAY INVISIBLE (12 -13);
FORCEPROP 2 LAST CDS_XR_PAGE_TITLE CR-95 : @T6G_MB_LIB.T6G(SCH_1):PAGE95
J 0
(-7890 5250);
DISPLAY 0.638298 (-7890 5250);
PAINT PINK (-7890 5250);
DISPLAY INVISIBLE (-7890 5250);
FORCEADD DNS..2
(-8325 2275);
PAINT RED (-8325 2275);
FORCEPROP 2 LAST CDS_LIB mstr_misc
J 0
(-8325 2275);
DISPLAY INVISIBLE (-8325 2275);
FORCEPROP 1 LAST COMMENT_BODY TRUE
R 1
J 0
(-8250 2050);
DISPLAY 0.872340 (-8250 2050);
PAINT PEACH (-8250 2050);
DISPLAY INVISIBLE (-8250 2050);
WIRE 17 -1 (-5975 5400)(-5975 5350);
WIRE 17 -1 (-5975 5425)(-5975 5400);
WIRE 17 -1 (-5975 5350)(-5975 5300);
WIRE 17 -1 (-5975 5300)(-5975 5250);
WIRE 17 -1 (-5975 5425)(-5400 5425);
FORCEPROP 2 LAST SIG_NAME M_K_CPU0_SA_DQ<31:0>
J 0
(-5910 5435);
DISPLAY 0.489362 (-5910 5435);
WIRE 17 -1 (-7775 4000)(-7775 3950);
WIRE 17 -1 (-7775 4000)(-7775 4025);
WIRE 17 -1 (-7775 3900)(-7775 3950);
WIRE 17 -1 (-7775 3900)(-7775 3850);
WIRE 17 -1 (-7775 4025)(-8275 4025);
FORCEPROP 2 LAST SIG_NAME M_K_CPU0_SA_CB<7:0>
J 0
(-8225 4035);
DISPLAY 0.489362 (-8225 4035);
WIRE 17 -1 (-7775 3800)(-7775 3850);
WIRE 17 -1 (-7775 3750)(-7775 3800);
WIRE 17 -1 (-7775 3700)(-7775 3750);
WIRE 17 -1 (-7775 3650)(-7775 3700);
WIRE 17 -1 (-7775 3550)(-7775 3575);
WIRE 17 -1 (-7775 3550)(-7775 3500);
WIRE 17 -1 (-7775 3575)(-8275 3575);
FORCEPROP 2 LAST SIG_NAME M_K_CPU0_SB_CB<7:0>
J 0
(-8225 3585);
DISPLAY 0.489362 (-8225 3585);
WIRE 17 -1 (-7775 5100)(-7775 5150);
WIRE 17 -1 (-7775 5150)(-7775 5200);
WIRE 17 -1 (-7775 5200)(-7775 5250);
WIRE 17 -1 (-7775 5250)(-7775 5300);
WIRE 17 -1 (-7775 5300)(-7775 5350);
WIRE 17 -1 (-7775 5350)(-7775 5400);
WIRE 17 -1 (-7775 5400)(-7775 5425);
WIRE 17 -1 (-7775 5425)(-8275 5425);
FORCEPROP 2 LAST SIG_NAME M_K_CPU0_SA_CA<6:0>
J 0
(-8260 5435);
DISPLAY 0.489362 (-8260 5435);
WIRE 17 -1 (-7775 4700)(-7775 4750);
WIRE 17 -1 (-7775 4750)(-7775 4800);
WIRE 17 -1 (-7775 4800)(-7775 4850);
WIRE 17 -1 (-7775 4850)(-7775 4900);
WIRE 17 -1 (-7775 4900)(-7775 4950);
WIRE 17 -1 (-7775 4950)(-7775 5000);
WIRE 17 -1 (-7775 5000)(-7775 5025);
WIRE 17 -1 (-7775 5025)(-8275 5025);
FORCEPROP 2 LAST SIG_NAME M_K_CPU0_SB_CA<6:0>
J 0
(-8260 5035);
DISPLAY 0.489362 (-8260 5035);
WIRE 17 -1 (-7775 3450)(-7775 3500);
WIRE 17 -1 (-7775 3450)(-7775 3400);
WIRE 17 -1 (-7775 3350)(-7775 3400);
WIRE 17 -1 (-7775 3300)(-7775 3350);
WIRE 17 -1 (-7775 3250)(-7775 3300);
WIRE 17 -1 (-7775 3200)(-7775 3250);
WIRE 17 -1 (-5975 5250)(-5975 5200);
WIRE 17 -1 (-5975 5200)(-5975 5150);
WIRE 17 -1 (-5975 5150)(-5975 5100);
WIRE 17 -1 (-5975 5100)(-5975 5050);
WIRE 17 -1 (-5975 5050)(-5975 5000);
WIRE 17 -1 (-5975 5000)(-5975 4950);
WIRE 17 -1 (-5975 4950)(-5975 4900);
WIRE 17 -1 (-5975 4900)(-5975 4850);
WIRE 17 -1 (-5975 4850)(-5975 4800);
WIRE 17 -1 (-5975 4800)(-5975 4750);
WIRE 17 -1 (-5975 4750)(-5975 4700);
WIRE 17 -1 (-5975 4700)(-5975 4650);
WIRE 17 -1 (-5975 4600)(-5975 4650);
WIRE 17 -1 (-5975 4550)(-5975 4600);
WIRE 17 -1 (-5975 4500)(-5975 4550);
WIRE 17 -1 (-5975 4450)(-5975 4500);
WIRE 17 -1 (-5975 4450)(-5975 4400);
WIRE 17 -1 (-5975 4400)(-5975 4350);
WIRE 17 -1 (-5975 4350)(-5975 4300);
WIRE 17 -1 (-5975 4300)(-5975 4250);
WIRE 17 -1 (-5975 4250)(-5975 4200);
WIRE 17 -1 (-5975 4200)(-5975 4150);
WIRE 17 -1 (-5975 4150)(-5975 4100);
WIRE 17 -1 (-5975 4100)(-5975 4050);
WIRE 17 -1 (-5975 4000)(-5975 4050);
WIRE 17 -1 (-5975 3950)(-5975 4000);
WIRE 17 -1 (-5975 3900)(-5975 3950);
WIRE 17 -1 (-5975 3850)(-5975 3900);
WIRE 17 -1 (-5975 3750)(-5975 3700);
WIRE 17 -1 (-5975 3775)(-5975 3750);
WIRE 17 -1 (-5975 3700)(-5975 3650);
WIRE 17 -1 (-5975 3650)(-5975 3600);
WIRE 17 -1 (-5975 3775)(-5400 3775);
FORCEPROP 2 LAST SIG_NAME M_K_CPU0_SB_DQ<31:0>
J 0
(-5910 3785);
DISPLAY 0.489362 (-5910 3785);
WIRE 17 -1 (-5975 3600)(-5975 3550);
WIRE 17 -1 (-5975 3550)(-5975 3500);
WIRE 17 -1 (-5975 3500)(-5975 3450);
WIRE 17 -1 (-5975 3450)(-5975 3400);
WIRE 17 -1 (-5975 3400)(-5975 3350);
WIRE 17 -1 (-5975 3350)(-5975 3300);
WIRE 17 -1 (-5975 3300)(-5975 3250);
WIRE 17 -1 (-5975 3250)(-5975 3200);
WIRE 17 -1 (-5975 3200)(-5975 3150);
WIRE 17 -1 (-5975 3150)(-5975 3100);
WIRE 17 -1 (-5975 3100)(-5975 3050);
WIRE 17 -1 (-5975 3050)(-5975 3000);
WIRE 17 -1 (-5975 2950)(-5975 3000);
WIRE 17 -1 (-5975 2900)(-5975 2950);
WIRE 17 -1 (-5975 2850)(-5975 2900);
WIRE 17 -1 (-5975 2800)(-5975 2850);
WIRE 17 -1 (-5975 2800)(-5975 2750);
WIRE 17 -1 (-5975 2750)(-5975 2700);
WIRE 17 -1 (-5975 2700)(-5975 2650);
WIRE 17 -1 (-5975 2650)(-5975 2600);
WIRE 17 -1 (-5975 2600)(-5975 2550);
WIRE 17 -1 (-5975 2550)(-5975 2500);
WIRE 17 -1 (-5975 2500)(-5975 2450);
WIRE 17 -1 (-5975 2450)(-5975 2400);
WIRE 17 -1 (-5975 2350)(-5975 2400);
WIRE 17 -1 (-5975 2300)(-5975 2350);
WIRE 17 -1 (-5975 2250)(-5975 2300);
WIRE 17 -1 (-5975 2200)(-5975 2250);
WIRE 17 -1 (-3225 4375)(-3225 4275);
WIRE 17 -1 (-3225 4475)(-3225 4375);
WIRE 17 -1 (-3225 4275)(-3225 4175);
WIRE 17 -1 (-3225 4075)(-3225 4175);
WIRE 17 -1 (-3225 4575)(-3225 4475);
WIRE 17 -1 (-3225 4600)(-3225 4575);
WIRE 17 -1 (-3225 3975)(-3225 4075);
WIRE 17 -1 (-3225 3875)(-3225 3975);
WIRE 17 -1 (-3225 4600)(-2525 4600);
FORCEPROP 2 LAST SIG_NAME M_K_CPU0_SA_DQS_DN<9:0>
J 0
(-3160 4610);
DISPLAY 0.489362 (-3160 4610);
WIRE 17 -1 (-3425 4325)(-3425 4225);
WIRE 17 -1 (-3425 4425)(-3425 4325);
WIRE 17 -1 (-3425 4125)(-3425 4225);
WIRE 17 -1 (-3425 4025)(-3425 4125);
WIRE 17 -1 (-3425 4525)(-3425 4425);
WIRE 17 -1 (-3425 4625)(-3425 4525);
WIRE 17 -1 (-3425 3925)(-3425 4025);
WIRE 17 -1 (-3425 3925)(-3425 3825);
WIRE 17 -1 (-3425 4650)(-3425 4625);
WIRE 17 -1 (-3425 4650)(-2525 4650);
FORCEPROP 2 LAST SIG_NAME M_K_CPU0_SA_DQS_DP<9:0>
J 0
(-3160 4660);
DISPLAY 0.489362 (-3160 4660);
WIRE 17 -1 (-3425 3575)(-3425 3475);
WIRE 17 -1 (-3425 3600)(-3425 3575);
WIRE 17 -1 (-3425 3475)(-3425 3375);
WIRE 17 -1 (-3425 3375)(-3425 3275);
WIRE 17 -1 (-3425 3600)(-2525 3600);
FORCEPROP 2 LAST SIG_NAME M_K_CPU0_SB_DQS_DP<9:0>
J 0
(-3160 3610);
DISPLAY 0.489362 (-3160 3610);
WIRE 17 -1 (-3225 3425)(-3225 3325);
WIRE 17 -1 (-3225 3525)(-3225 3425);
WIRE 17 -1 (-3225 3325)(-3225 3225);
WIRE 17 -1 (-3225 3225)(-3225 3125);
WIRE 17 -1 (-3225 3550)(-3225 3525);
WIRE 17 -1 (-3225 3550)(-2525 3550);
FORCEPROP 2 LAST SIG_NAME M_K_CPU0_SB_DQS_DN<9:0>
J 0
(-3160 3560);
DISPLAY 0.489362 (-3160 3560);
WIRE 17 -1 (-3425 3275)(-3425 3175);
WIRE 17 -1 (-3425 3075)(-3425 3175);
WIRE 17 -1 (-3425 2975)(-3425 3075);
WIRE 17 -1 (-3425 2875)(-3425 2975);
WIRE 17 -1 (-3225 3775)(-3225 3675);
WIRE 17 -1 (-3225 3875)(-3225 3775);
WIRE 17 -1 (-3425 3825)(-3425 3725);
WIRE 17 -1 (-3225 2725)(-3225 2625);
WIRE 17 -1 (-3225 2825)(-3225 2725);
WIRE 17 -1 (-3225 2825)(-3225 2925);
WIRE 17 -1 (-3225 2925)(-3225 3025);
WIRE 17 -1 (-3225 3025)(-3225 3125);
WIRE 17 -1 (-3425 2775)(-3425 2675);
WIRE 17 -1 (-3425 2875)(-3425 2775);
WIRE 16 -1 (-6425 1100)(-6425 1175);
WIRE 16 -1 (-8600 3025)(-8600 3100);
WIRE 16 -1 (-8350 2375)(-8350 2400);
WIRE 16 -1 (-7475 2775)(-7575 2775);
FORCEPROP 2 LAST SIG_NAME I3C_SPD_DDRK_CPU0_SCL
J 0
(-7960 2785);
DISPLAY 0.446809 (-7960 2785);
FORCEPROP 2 LASTPROP $XRERR UNIQUE?
J 0
(-8200 2785);
DISPLAY 0.638298 (-8200 2785);
PAINT MONO (-8200 2785);
DISPLAY INVISIBLE (-8200 2785);
WIRE 16 -1 (-7575 2775)(-7575 2675);
WIRE 16 -1 (-7575 2675)(-7675 2675);
WIRE 16 -1 (-7875 2675)(-8300 2675);
FORCEPROP 2 LAST SIG_NAME I3C_SPD_DDRGL_CPU0_SCL
J 0
(-8360 2685);
DISPLAY 0.489362 (-8360 2685);
WIRE 16 -1 (-8350 2175)(-8350 2125);
WIRE 16 -1 (-8150 2125)(-8350 2125);
WIRE 16 -1 (-8350 2125)(-8375 2125);
WIRE 16 -1 (-8150 2125)(-8150 2525);
WIRE 16 -1 (-7475 2525)(-8150 2525);
FORCEPROP 2 LAST SIG_NAME PWRGD_CHK_CPU0_DIMM
J 0
(-8060 2535);
DISPLAY 0.489362 (-8060 2535);
FORCEPROP 2 LASTPROP $XRERR UNIQUE?
J 0
(-8300 2535);
DISPLAY 0.638298 (-8300 2535);
PAINT MONO (-8300 2535);
DISPLAY INVISIBLE (-8300 2535);
WIRE 16 -1 (-7475 2125)(-8050 2125);
FORCEPROP 2 LAST SIG_NAME TP_CHK_CPU0_DIMM_RFU_0
J 0
(-8060 2135);
DISPLAY 0.489362 (-8060 2135);
FORCEPROP 2 LASTPROP $XRERR UNIQUE?
J 0
(-8290 2125);
DISPLAY 0.638298 (-8290 2125);
PAINT MONO (-8290 2125);
DISPLAY INVISIBLE (-8290 2125);
WIRE 16 -1 (-7475 2175)(-8050 2175);
FORCEPROP 2 LAST SIG_NAME TP_CHK_CPU0_DIMM_RFU_1
J 0
(-8060 2185);
DISPLAY 0.489362 (-8060 2185);
FORCEPROP 2 LASTPROP $XRERR UNIQUE?
J 0
(-8290 2175);
DISPLAY 0.638298 (-8290 2175);
PAINT MONO (-8290 2175);
DISPLAY INVISIBLE (-8290 2175);
WIRE 16 -1 (-7475 2225)(-8050 2225);
FORCEPROP 2 LAST SIG_NAME TP_CHK_CPU0_DIMM_RFU_2
J 0
(-8060 2235);
DISPLAY 0.489362 (-8060 2235);
FORCEPROP 2 LASTPROP $XRERR UNIQUE?
J 0
(-8290 2225);
DISPLAY 0.638298 (-8290 2225);
PAINT MONO (-8290 2225);
DISPLAY INVISIBLE (-8290 2225);
WIRE 16 -1 (-7475 2375)(-8050 2375);
FORCEPROP 2 LAST SIG_NAME TP_CHK_CPU0_DIMM_RFU_5
J 0
(-8060 2385);
DISPLAY 0.489362 (-8060 2385);
FORCEPROP 2 LASTPROP $XRERR UNIQUE?
J 0
(-8290 2375);
DISPLAY 0.638298 (-8290 2375);
PAINT MONO (-8290 2375);
DISPLAY INVISIBLE (-8290 2375);
WIRE 16 -1 (-7475 2825)(-8275 2825);
FORCEPROP 2 LAST SIG_NAME I3C_SPD_DDRGL_CPU0_SDA
J 0
(-8285 2835);
DISPLAY 0.489362 (-8285 2835);
WIRE 16 -1 (-7475 2425)(-8050 2425);
FORCEPROP 2 LAST SIG_NAME TP_CHK_CPU0_DIMM_RFU_6
J 0
(-8060 2435);
DISPLAY 0.489362 (-8060 2435);
FORCEPROP 2 LASTPROP $XRERR UNIQUE?
J 0
(-8290 2425);
DISPLAY 0.638298 (-8290 2425);
PAINT MONO (-8290 2425);
DISPLAY INVISIBLE (-8290 2425);
WIRE 16 -1 (-7475 2325)(-8050 2325);
FORCEPROP 2 LAST SIG_NAME TP_CHK_CPU0_DIMM_RFU_4
J 0
(-8060 2335);
DISPLAY 0.489362 (-8060 2335);
FORCEPROP 2 LASTPROP $XRERR UNIQUE?
J 0
(-8290 2325);
DISPLAY 0.638298 (-8290 2325);
PAINT MONO (-8290 2325);
DISPLAY INVISIBLE (-8290 2325);
WIRE 16 -1 (-7475 2275)(-8050 2275);
FORCEPROP 2 LAST SIG_NAME TP_CHK_CPU0_DIMM_RFU_3
J 0
(-8060 2285);
DISPLAY 0.489362 (-8060 2285);
FORCEPROP 2 LASTPROP $XRERR UNIQUE?
J 0
(-8290 2275);
DISPLAY 0.638298 (-8290 2275);
PAINT MONO (-8290 2275);
DISPLAY INVISIBLE (-8290 2275);
WIRE 16 -1 (-8975 2125)(-8575 2125);
FORCEPROP 2 LAST SIG_NAME PWRGD_CHGL_CPU0
J 0
(-8960 2135);
DISPLAY 0.489362 (-8960 2135);
WIRE 16 -1 (-7475 2875)(-8275 2875);
FORCEPROP 2 LAST SIG_NAME PD_CHK_CPU0_DIMM_SAA
J 0
(-8250 2885);
DISPLAY 0.489362 (-8250 2885);
WIRE 16 -1 (-8500 2925)(-7475 2925);
WIRE 16 -1 (-8500 3325)(-8500 2925);
WIRE 16 -1 (-8500 3350)(-8500 3325);
WIRE 16 -1 (-8600 3325)(-8500 3325);
WIRE 16 -1 (-8600 3300)(-8600 3325);
WIRE 16 -1 (-7475 1975)(-8275 1975);
FORCEPROP 2 LAST SIG_NAME M_K_CPU0_SA_RSP<0>
J 0
(-8225 1985);
DISPLAY 0.489362 (-8225 1985);
WIRE 16 -1 (-7475 3025)(-8100 3025);
FORCEPROP 2 LAST SIG_NAME M_K_CPU0_ALERT_N
J 0
(-8085 3035);
DISPLAY 0.489362 (-8085 3035);
WIRE 16 -1 (-7475 4075)(-8275 4075);
FORCEPROP 2 LAST SIG_NAME M_K_CPU0_CLK_DN<0>
J 0
(-8225 4085);
DISPLAY 0.489362 (-8225 4085);
WIRE 16 -1 (-7475 4125)(-8275 4125);
FORCEPROP 2 LAST SIG_NAME M_K_CPU0_CLK_DP<0>
J 0
(-8225 4135);
DISPLAY 0.489362 (-8225 4135);
WIRE 16 -1 (-7475 1925)(-8275 1925);
FORCEPROP 2 LAST SIG_NAME M_K_CPU0_SB_RSP<0>
J 0
(-8225 1935);
DISPLAY 0.489362 (-8225 1935);
WIRE 16 -1 (-7475 4375)(-8275 4375);
FORCEPROP 2 LAST SIG_NAME M_K_CPU0_SA_CS_N<0>
J 0
(-8225 4385);
DISPLAY 0.489362 (-8225 4385);
WIRE 16 -1 (-7475 4425)(-8275 4425);
FORCEPROP 2 LAST SIG_NAME M_K_CPU0_SA_CS_N<1>
J 0
(-8225 4435);
DISPLAY 0.489362 (-8225 4435);
WIRE 16 -1 (-7475 5375)(-7675 5375);
WIRE 16 -1 (-7475 5325)(-7675 5325);
WIRE 16 -1 (-7475 5275)(-7675 5275);
WIRE 16 -1 (-7475 5225)(-7675 5225);
WIRE 16 -1 (-325 5325)(-325 5275);
WIRE 16 -1 (-325 5325)(-625 5325);
WIRE 16 -1 (-325 5275)(-325 5225);
WIRE 16 -1 (-325 5275)(-625 5275);
WIRE 16 -1 (-325 5225)(-325 5175);
WIRE 16 -1 (-325 5225)(-625 5225);
WIRE 16 -1 (-325 5175)(-325 5125);
WIRE 16 -1 (-325 5175)(-625 5175);
WIRE 16 -1 (-325 5125)(-625 5125);
WIRE 16 -1 (-325 5125)(-325 5075);
WIRE 16 -1 (-325 5075)(-325 5025);
WIRE 16 -1 (-325 5075)(-625 5075);
WIRE 16 -1 (-325 5025)(-325 4975);
WIRE 16 -1 (-325 5025)(-625 5025);
WIRE 16 -1 (-325 4975)(-325 4925);
WIRE 16 -1 (-325 4975)(-625 4975);
WIRE 16 -1 (-325 4925)(-325 4875);
WIRE 16 -1 (-325 4925)(-625 4925);
WIRE 16 -1 (-325 4875)(-325 4825);
WIRE 16 -1 (-325 4875)(-625 4875);
WIRE 16 -1 (-325 4825)(-325 4775);
WIRE 16 -1 (-325 4825)(-625 4825);
WIRE 16 -1 (-325 4775)(-325 4725);
WIRE 16 -1 (-325 4775)(-625 4775);
WIRE 16 -1 (-325 4725)(-325 4675);
WIRE 16 -1 (-325 4725)(-625 4725);
WIRE 16 -1 (-325 4675)(-325 4625);
WIRE 16 -1 (-325 4675)(-625 4675);
WIRE 16 -1 (-325 4625)(-325 4575);
WIRE 16 -1 (-325 4625)(-625 4625);
WIRE 16 -1 (-325 4575)(-325 4525);
WIRE 16 -1 (-325 4575)(-625 4575);
WIRE 16 -1 (-325 4525)(-325 4475);
WIRE 16 -1 (-325 4525)(-625 4525);
WIRE 16 -1 (-325 4475)(-325 4425);
WIRE 16 -1 (-325 4475)(-625 4475);
WIRE 16 -1 (-325 4425)(-325 4375);
WIRE 16 -1 (-325 4425)(-625 4425);
WIRE 16 -1 (-325 4375)(-325 4325);
WIRE 16 -1 (-325 4375)(-625 4375);
WIRE 16 -1 (-325 4325)(-325 4275);
WIRE 16 -1 (-325 4325)(-625 4325);
WIRE 16 -1 (-325 4275)(-325 4225);
WIRE 16 -1 (-325 4275)(-625 4275);
WIRE 16 -1 (-325 4225)(-325 4175);
WIRE 16 -1 (-325 4225)(-625 4225);
WIRE 16 -1 (-325 4175)(-325 4125);
WIRE 16 -1 (-325 4175)(-625 4175);
WIRE 16 -1 (-325 4125)(-625 4125);
WIRE 16 -1 (-325 4125)(-325 4075);
WIRE 16 -1 (-325 4075)(-325 4025);
WIRE 16 -1 (-325 4075)(-625 4075);
WIRE 16 -1 (-325 4025)(-325 3975);
WIRE 16 -1 (-325 4025)(-625 4025);
WIRE 16 -1 (-325 3975)(-325 3925);
WIRE 16 -1 (-325 3975)(-625 3975);
WIRE 16 -1 (-325 3925)(-325 3875);
WIRE 16 -1 (-325 3925)(-625 3925);
WIRE 16 -1 (-325 3875)(-325 3825);
WIRE 16 -1 (-325 3875)(-625 3875);
WIRE 16 -1 (-325 3825)(-325 3775);
WIRE 16 -1 (-325 3825)(-625 3825);
WIRE 16 -1 (-325 3775)(-325 3725);
WIRE 16 -1 (-325 3775)(-625 3775);
WIRE 16 -1 (-325 3725)(-325 3675);
WIRE 16 -1 (-325 3725)(-625 3725);
WIRE 16 -1 (-325 3675)(-325 3625);
WIRE 16 -1 (-325 3675)(-625 3675);
WIRE 16 -1 (-325 3625)(-325 3575);
WIRE 16 -1 (-325 3625)(-625 3625);
WIRE 16 -1 (-325 3575)(-325 3525);
WIRE 16 -1 (-325 3575)(-625 3575);
WIRE 16 -1 (-325 3525)(-325 3475);
WIRE 16 -1 (-325 3525)(-625 3525);
WIRE 16 -1 (-325 3475)(-325 3425);
WIRE 16 -1 (-325 3475)(-625 3475);
WIRE 16 -1 (-325 3425)(-325 3375);
WIRE 16 -1 (-325 3425)(-625 3425);
WIRE 16 -1 (-325 3375)(-325 3325);
WIRE 16 -1 (-325 3375)(-625 3375);
WIRE 16 -1 (-325 3325)(-325 3275);
WIRE 16 -1 (-325 3325)(-625 3325);
WIRE 16 -1 (-325 3275)(-325 3225);
WIRE 16 -1 (-325 3275)(-625 3275);
WIRE 16 -1 (-325 3225)(-325 3175);
WIRE 16 -1 (-325 3225)(-625 3225);
WIRE 16 -1 (-325 3175)(-325 3125);
WIRE 16 -1 (-325 3175)(-625 3175);
WIRE 16 -1 (-325 3125)(-325 3075);
WIRE 16 -1 (-325 3125)(-625 3125);
WIRE 16 -1 (-325 3075)(-625 3075);
WIRE 16 -1 (-325 3075)(-325 3025);
WIRE 16 -1 (-325 3025)(-325 2975);
WIRE 16 -1 (-325 3025)(-625 3025);
WIRE 16 -1 (-325 2975)(-325 2925);
WIRE 16 -1 (-325 2975)(-625 2975);
WIRE 16 -1 (-325 2925)(-325 2875);
WIRE 16 -1 (-325 2925)(-625 2925);
WIRE 16 -1 (-325 2875)(-325 2825);
WIRE 16 -1 (-325 2875)(-625 2875);
WIRE 16 -1 (-325 2825)(-325 2775);
WIRE 16 -1 (-325 2825)(-625 2825);
WIRE 16 -1 (-325 2775)(-325 2725);
WIRE 16 -1 (-325 2775)(-625 2775);
WIRE 16 -1 (-325 2725)(-325 2675);
WIRE 16 -1 (-325 2725)(-625 2725);
WIRE 16 -1 (-325 2675)(-325 2625);
WIRE 16 -1 (-325 2675)(-625 2675);
WIRE 16 -1 (-325 2625)(-325 2575);
WIRE 16 -1 (-325 2625)(-625 2625);
WIRE 16 -1 (-325 2575)(-325 2525);
WIRE 16 -1 (-325 2575)(-625 2575);
WIRE 16 -1 (-325 2525)(-325 2475);
WIRE 16 -1 (-325 2525)(-625 2525);
WIRE 16 -1 (-325 2475)(-325 2425);
WIRE 16 -1 (-325 2475)(-625 2475);
WIRE 16 -1 (-325 2425)(-325 2375);
WIRE 16 -1 (-325 2425)(-625 2425);
WIRE 16 -1 (-325 2375)(-325 2325);
WIRE 16 -1 (-325 2375)(-625 2375);
WIRE 16 -1 (-325 2325)(-325 2275);
WIRE 16 -1 (-325 2325)(-625 2325);
WIRE 16 -1 (-325 2275)(-325 2225);
WIRE 16 -1 (-325 2275)(-625 2275);
WIRE 16 -1 (-325 2225)(-325 2175);
WIRE 16 -1 (-325 2225)(-625 2225);
WIRE 16 -1 (-325 2175)(-325 2075);
WIRE 16 -1 (-325 2175)(-625 2175);
WIRE 16 -1 (-325 2075)(-325 2025);
WIRE 16 -1 (-325 2075)(-625 2075);
WIRE 16 -1 (-325 2025)(-325 1975);
WIRE 16 -1 (-325 2025)(-625 2025);
WIRE 16 -1 (-325 1975)(-325 1725);
WIRE 16 -1 (-325 1975)(-625 1975);
WIRE 16 -1 (-2125 5225)(-1825 5225);
WIRE 16 -1 (-2125 5275)(-2125 5225);
WIRE 16 -1 (-1825 5275)(-2125 5275);
WIRE 16 -1 (-2125 5275)(-2125 5325);
WIRE 16 -1 (-1825 5325)(-2125 5325);
WIRE 16 -1 (-2125 5325)(-2125 6200);
WIRE 16 -1 (-2250 6200)(-2125 6200);
WIRE 16 -1 (-2250 6200)(-2825 6200);
WIRE 16 -1 (-2250 6200)(-2250 6100);
WIRE 16 -1 (-2825 6200)(-2825 6275);
WIRE 16 -1 (-2825 6100)(-2825 6200);
WIRE 16 -1 (-1825 5175)(-2125 5175);
WIRE 16 -1 (-2125 5175)(-2125 5125);
WIRE 16 -1 (-1825 5125)(-2125 5125);
WIRE 16 -1 (-2125 5125)(-2125 5075);
WIRE 16 -1 (-1825 5075)(-2125 5075);
WIRE 16 -1 (-2125 5075)(-2125 5025);
WIRE 16 -1 (-1825 5025)(-2125 5025);
WIRE 16 -1 (-2125 5025)(-2125 4975);
WIRE 16 -1 (-1825 4975)(-2125 4975);
WIRE 16 -1 (-2125 4975)(-2125 4925);
WIRE 16 -1 (-1825 4925)(-2125 4925);
WIRE 16 -1 (-2125 4925)(-2125 4875);
WIRE 16 -1 (-1825 4875)(-2125 4875);
WIRE 16 -1 (-2125 4875)(-2125 4825);
WIRE 16 -1 (-1825 4825)(-2125 4825);
WIRE 16 -1 (-2125 4825)(-2125 4775);
WIRE 16 -1 (-1825 4775)(-2125 4775);
WIRE 16 -1 (-2125 4775)(-2125 4725);
WIRE 16 -1 (-1825 4725)(-2125 4725);
WIRE 16 -1 (-2125 4725)(-2125 4675);
WIRE 16 -1 (-1825 4675)(-2125 4675);
WIRE 16 -1 (-2125 4675)(-2125 4625);
WIRE 16 -1 (-1825 4625)(-2125 4625);
WIRE 16 -1 (-2125 4625)(-2125 4575);
WIRE 16 -1 (-1825 4575)(-2125 4575);
WIRE 16 -1 (-2125 4575)(-2125 4525);
WIRE 16 -1 (-1825 4525)(-2125 4525);
WIRE 16 -1 (-2125 4525)(-2125 4475);
WIRE 16 -1 (-1825 4475)(-2125 4475);
WIRE 16 -1 (-2125 4475)(-2125 4425);
WIRE 16 -1 (-1825 4425)(-2125 4425);
WIRE 16 -1 (-2125 4425)(-2125 4375);
WIRE 16 -1 (-1825 4375)(-2125 4375);
WIRE 16 -1 (-2125 4375)(-2125 4325);
WIRE 16 -1 (-1825 4325)(-2125 4325);
WIRE 16 -1 (-2125 4325)(-2125 4275);
WIRE 16 -1 (-1825 4275)(-2125 4275);
WIRE 16 -1 (-2125 4275)(-2125 4225);
WIRE 16 -1 (-1825 4225)(-2125 4225);
WIRE 16 -1 (-2125 4225)(-2125 4175);
WIRE 16 -1 (-1825 4175)(-2125 4175);
WIRE 16 -1 (-2125 4175)(-2125 4125);
WIRE 16 -1 (-1825 4125)(-2125 4125);
WIRE 16 -1 (-2125 4125)(-2125 4075);
WIRE 16 -1 (-1825 4075)(-2125 4075);
WIRE 16 -1 (-2125 4075)(-2125 4025);
WIRE 16 -1 (-1825 4025)(-2125 4025);
WIRE 16 -1 (-2125 4025)(-2125 3975);
WIRE 16 -1 (-1825 3975)(-2125 3975);
WIRE 16 -1 (-2125 3975)(-2125 3925);
WIRE 16 -1 (-1825 3925)(-2125 3925);
WIRE 16 -1 (-2125 3925)(-2125 3875);
WIRE 16 -1 (-1825 3875)(-2125 3875);
WIRE 16 -1 (-2125 3875)(-2125 3825);
WIRE 16 -1 (-1825 3825)(-2125 3825);
WIRE 16 -1 (-2125 3825)(-2125 3775);
WIRE 16 -1 (-1825 3775)(-2125 3775);
WIRE 16 -1 (-2125 3775)(-2125 3725);
WIRE 16 -1 (-1825 3725)(-2125 3725);
WIRE 16 -1 (-2125 3725)(-2125 3675);
WIRE 16 -1 (-1825 3675)(-2125 3675);
WIRE 16 -1 (-2125 3675)(-2125 3625);
WIRE 16 -1 (-1825 3625)(-2125 3625);
WIRE 16 -1 (-2125 3625)(-2125 3575);
WIRE 16 -1 (-1825 3575)(-2125 3575);
WIRE 16 -1 (-2125 3575)(-2125 3525);
WIRE 16 -1 (-1825 3525)(-2125 3525);
WIRE 16 -1 (-2125 3525)(-2125 3475);
WIRE 16 -1 (-1825 3475)(-2125 3475);
WIRE 16 -1 (-2125 3475)(-2125 3425);
WIRE 16 -1 (-1825 3425)(-2125 3425);
WIRE 16 -1 (-2125 3425)(-2125 3375);
WIRE 16 -1 (-1825 3375)(-2125 3375);
WIRE 16 -1 (-2125 3375)(-2125 3325);
WIRE 16 -1 (-1825 3325)(-2125 3325);
WIRE 16 -1 (-2125 3325)(-2125 3275);
WIRE 16 -1 (-1825 3275)(-2125 3275);
WIRE 16 -1 (-2125 3275)(-2125 3225);
WIRE 16 -1 (-1825 3225)(-2125 3225);
WIRE 16 -1 (-2125 3225)(-2125 3175);
WIRE 16 -1 (-1825 3175)(-2125 3175);
WIRE 16 -1 (-2125 3175)(-2125 3125);
WIRE 16 -1 (-1825 3125)(-2125 3125);
WIRE 16 -1 (-2125 3125)(-2125 3075);
WIRE 16 -1 (-1825 3075)(-2125 3075);
WIRE 16 -1 (-2125 3075)(-2125 3025);
WIRE 16 -1 (-1825 3025)(-2125 3025);
WIRE 16 -1 (-2125 3025)(-2125 2975);
WIRE 16 -1 (-1825 2975)(-2125 2975);
WIRE 16 -1 (-2125 2975)(-2125 2925);
WIRE 16 -1 (-1825 2925)(-2125 2925);
WIRE 16 -1 (-2125 2925)(-2125 2875);
WIRE 16 -1 (-1825 2875)(-2125 2875);
WIRE 16 -1 (-2125 2875)(-2125 2825);
WIRE 16 -1 (-1825 2825)(-2125 2825);
WIRE 16 -1 (-2125 2825)(-2125 2775);
WIRE 16 -1 (-1825 2775)(-2125 2775);
WIRE 16 -1 (-2125 2775)(-2125 2725);
WIRE 16 -1 (-1825 2725)(-2125 2725);
WIRE 16 -1 (-2125 2725)(-2125 2675);
WIRE 16 -1 (-1825 2675)(-2125 2675);
WIRE 16 -1 (-2125 2675)(-2125 2625);
WIRE 16 -1 (-1825 2625)(-2125 2625);
WIRE 16 -1 (-2125 2625)(-2125 2575);
WIRE 16 -1 (-1825 2575)(-2125 2575);
WIRE 16 -1 (-2125 2575)(-2125 2525);
WIRE 16 -1 (-1825 2525)(-2125 2525);
WIRE 16 -1 (-2125 2525)(-2125 2475);
WIRE 16 -1 (-1825 2475)(-2125 2475);
WIRE 16 -1 (-2125 2475)(-2125 2425);
WIRE 16 -1 (-1825 2425)(-2125 2425);
WIRE 16 -1 (-2125 2425)(-2125 2375);
WIRE 16 -1 (-1825 2375)(-2125 2375);
WIRE 16 -1 (-2125 2375)(-2125 2325);
WIRE 16 -1 (-1825 2325)(-2125 2325);
WIRE 16 -1 (-2125 2325)(-2125 2275);
WIRE 16 -1 (-1825 2275)(-2125 2275);
WIRE 16 -1 (-2125 2275)(-2125 2225);
WIRE 16 -1 (-1825 2225)(-2125 2225);
WIRE 16 -1 (-2125 2225)(-2125 2175);
WIRE 16 -1 (-1825 2175)(-2125 2175);
WIRE 16 -1 (-2125 2175)(-2125 2125);
WIRE 16 -1 (-2125 2125)(-2125 2075);
WIRE 16 -1 (-1825 2125)(-2125 2125);
WIRE 16 -1 (-1825 2075)(-2125 2075);
WIRE 16 -1 (-2125 2075)(-2125 1950);
WIRE 16 -1 (-3675 3550)(-3525 3550);
WIRE 16 -1 (-3675 3500)(-3325 3500);
WIRE 16 -1 (-3675 4600)(-3525 4600);
WIRE 16 -1 (-3675 4550)(-3325 4550);
WIRE 16 -1 (-3525 4500)(-3675 4500);
WIRE 16 -1 (-3675 4450)(-3325 4450);
WIRE 16 -1 (-3675 3300)(-3325 3300);
WIRE 16 -1 (-3525 4400)(-3675 4400);
WIRE 16 -1 (-3525 3250)(-3675 3250);
WIRE 16 -1 (-3675 3200)(-3325 3200);
WIRE 16 -1 (-3675 4250)(-3325 4250);
WIRE 16 -1 (-3675 3150)(-3525 3150);
WIRE 16 -1 (-3675 3100)(-3325 3100);
WIRE 16 -1 (-3675 4200)(-3525 4200);
WIRE 16 -1 (-3675 4150)(-3325 4150);
WIRE 16 -1 (-3525 3050)(-3675 3050);
WIRE 16 -1 (-3675 3000)(-3325 3000);
WIRE 16 -1 (-3525 4100)(-3675 4100);
WIRE 16 -1 (-3675 4050)(-3325 4050);
WIRE 16 -1 (-3525 2950)(-3675 2950);
WIRE 16 -1 (-3675 2900)(-3325 2900);
WIRE 16 -1 (-3525 4000)(-3675 4000);
WIRE 16 -1 (-3675 3950)(-3325 3950);
WIRE 16 -1 (-3525 2850)(-3675 2850);
WIRE 16 -1 (-3675 2800)(-3325 2800);
WIRE 16 -1 (-3525 3900)(-3675 3900);
WIRE 16 -1 (-3675 3850)(-3325 3850);
WIRE 16 -1 (-3675 2750)(-3525 2750);
WIRE 16 -1 (-3675 2700)(-3325 2700);
WIRE 16 -1 (-3675 3800)(-3525 3800);
WIRE 16 -1 (-3675 3750)(-3325 3750);
WIRE 16 -1 (-3525 2650)(-3675 2650);
WIRE 16 -1 (-3675 2600)(-3325 2600);
WIRE 16 -1 (-3525 3700)(-3675 3700);
WIRE 16 -1 (-3675 3650)(-3325 3650);
WIRE 16 -1 (-3525 3350)(-3675 3350);
WIRE 16 -1 (-3675 3400)(-3325 3400);
WIRE 16 -1 (-3525 3450)(-3675 3450);
WIRE 16 -1 (-3525 4300)(-3675 4300);
WIRE 16 -1 (-3675 4350)(-3325 4350);
WIRE 16 -1 (-7475 3075)(-8100 3075);
FORCEPROP 2 LAST SIG_NAME M_K_CPU0_RESET_N
J 0
(-8085 3085);
DISPLAY 0.489362 (-8085 3085);
WIRE 16 -1 (-7475 4525)(-8275 4525);
FORCEPROP 2 LAST SIG_NAME M_K_CPU0_SB_PAR
J 0
(-8225 4535);
DISPLAY 0.489362 (-8225 4535);
WIRE 16 -1 (-7475 4575)(-8275 4575);
FORCEPROP 2 LAST SIG_NAME M_K_CPU0_SA_PAR
J 0
(-8225 4585);
DISPLAY 0.489362 (-8225 4585);
WIRE 16 -1 (-6075 2175)(-6275 2175);
WIRE 16 -1 (-6075 2225)(-6275 2225);
WIRE 16 -1 (-6075 2275)(-6275 2275);
WIRE 16 -1 (-6275 2325)(-6075 2325);
WIRE 16 -1 (-6075 2375)(-6275 2375);
WIRE 16 -1 (-6075 2425)(-6275 2425);
WIRE 16 -1 (-6075 2475)(-6275 2475);
WIRE 16 -1 (-6275 2525)(-6075 2525);
WIRE 16 -1 (-6075 2575)(-6275 2575);
WIRE 16 -1 (-6075 2625)(-6275 2625);
WIRE 16 -1 (-6075 2675)(-6275 2675);
WIRE 16 -1 (-6275 2725)(-6075 2725);
WIRE 16 -1 (-6075 2775)(-6275 2775);
WIRE 16 -1 (-6075 2825)(-6275 2825);
WIRE 16 -1 (-6075 2875)(-6275 2875);
WIRE 16 -1 (-6275 2925)(-6075 2925);
WIRE 16 -1 (-6075 2975)(-6275 2975);
WIRE 16 -1 (-6075 3025)(-6275 3025);
WIRE 16 -1 (-6075 3075)(-6275 3075);
WIRE 16 -1 (-6275 3125)(-6075 3125);
WIRE 16 -1 (-6075 3175)(-6275 3175);
WIRE 16 -1 (-6075 3225)(-6275 3225);
WIRE 16 -1 (-6075 3275)(-6275 3275);
WIRE 16 -1 (-6275 3325)(-6075 3325);
WIRE 16 -1 (-6075 3375)(-6275 3375);
WIRE 16 -1 (-6075 3425)(-6275 3425);
WIRE 16 -1 (-6075 3475)(-6275 3475);
WIRE 16 -1 (-6275 3525)(-6075 3525);
WIRE 16 -1 (-6075 3575)(-6275 3575);
WIRE 16 -1 (-6075 3625)(-6275 3625);
WIRE 16 -1 (-6075 3675)(-6275 3675);
WIRE 16 -1 (-6275 3725)(-6075 3725);
WIRE 16 -1 (-6075 3825)(-6275 3825);
WIRE 16 -1 (-6075 3875)(-6275 3875);
WIRE 16 -1 (-6075 3925)(-6275 3925);
WIRE 16 -1 (-6275 3975)(-6075 3975);
WIRE 16 -1 (-6075 4025)(-6275 4025);
WIRE 16 -1 (-6075 4075)(-6275 4075);
WIRE 16 -1 (-6075 4125)(-6275 4125);
WIRE 16 -1 (-6275 4175)(-6075 4175);
WIRE 16 -1 (-6075 4225)(-6275 4225);
WIRE 16 -1 (-6075 4275)(-6275 4275);
WIRE 16 -1 (-6075 4325)(-6275 4325);
WIRE 16 -1 (-6275 4375)(-6075 4375);
WIRE 16 -1 (-6075 4425)(-6275 4425);
WIRE 16 -1 (-6075 4475)(-6275 4475);
WIRE 16 -1 (-6075 4525)(-6275 4525);
WIRE 16 -1 (-6275 4575)(-6075 4575);
WIRE 16 -1 (-6075 4625)(-6275 4625);
WIRE 16 -1 (-6075 4675)(-6275 4675);
WIRE 16 -1 (-6075 4725)(-6275 4725);
WIRE 16 -1 (-6275 4775)(-6075 4775);
WIRE 16 -1 (-6075 4825)(-6275 4825);
WIRE 16 -1 (-6075 4875)(-6275 4875);
WIRE 16 -1 (-6075 4925)(-6275 4925);
WIRE 16 -1 (-6275 4975)(-6075 4975);
WIRE 16 -1 (-6075 5025)(-6275 5025);
WIRE 16 -1 (-6075 5075)(-6275 5075);
WIRE 16 -1 (-6075 5125)(-6275 5125);
WIRE 16 -1 (-6275 5175)(-6075 5175);
WIRE 16 -1 (-6075 5225)(-6275 5225);
WIRE 16 -1 (-6075 5275)(-6275 5275);
WIRE 16 -1 (-6075 5325)(-6275 5325);
WIRE 16 -1 (-7475 4275)(-8275 4275);
FORCEPROP 2 LAST SIG_NAME M_K_CPU0_SB_CS_N<1>
J 0
(-8225 4285);
DISPLAY 0.489362 (-8225 4285);
WIRE 16 -1 (-7475 4225)(-8275 4225);
FORCEPROP 2 LAST SIG_NAME M_K_CPU0_SB_CS_N<0>
J 0
(-8225 4235);
DISPLAY 0.489362 (-8225 4235);
WIRE 16 -1 (-7475 3175)(-7675 3175);
WIRE 16 -1 (-7475 3225)(-7675 3225);
WIRE 16 -1 (-7475 3275)(-7675 3275);
WIRE 16 -1 (-7475 3325)(-7675 3325);
WIRE 16 -1 (-7475 3375)(-7675 3375);
WIRE 16 -1 (-7475 3425)(-7675 3425);
WIRE 16 -1 (-7475 3475)(-7675 3475);
WIRE 16 -1 (-7475 3625)(-7675 3625);
WIRE 16 -1 (-7475 3725)(-7675 3725);
WIRE 16 -1 (-7475 3775)(-7675 3775);
WIRE 16 -1 (-7475 3875)(-7675 3875);
WIRE 16 -1 (-7475 3925)(-7675 3925);
WIRE 16 -1 (-7475 4975)(-7675 4975);
WIRE 16 -1 (-7475 4925)(-7675 4925);
WIRE 16 -1 (-7475 4875)(-7675 4875);
WIRE 16 -1 (-7475 4825)(-7675 4825);
WIRE 16 -1 (-7475 4775)(-7675 4775);
WIRE 16 -1 (-7475 5175)(-7675 5175);
WIRE 16 -1 (-7475 4725)(-7675 4725);
WIRE 16 -1 (-7475 5125)(-7675 5125);
WIRE 16 -1 (-7475 4675)(-7675 4675);
WIRE 16 -1 (-7475 5075)(-7675 5075);
WIRE 16 -1 (-7475 3525)(-7675 3525);
WIRE 16 -1 (-7475 3675)(-7675 3675);
WIRE 16 -1 (-7475 3825)(-7675 3825);
WIRE 16 -1 (-7475 3975)(-7675 3975);
WIRE 16 -1 (-6275 5375)(-6075 5375);
WIRE 16 -1 (-2250 5775)(-2825 5775);
WIRE 16 -1 (-2250 5775)(-2250 5900);
WIRE 16 -1 (-2825 5775)(-2825 5900);
WIRE 16 -1 (-2825 5775)(-2825 5700);
WIRE 16 -1 (-6425 1450)(-6425 1375);
WIRE 16 -1 (-6425 1450)(-7150 1450);
FORCEPROP 2 LAST SIG_NAME PD_CHK_CPU0_DIMM_SAA
J 0
(-7135 1460);
DISPLAY 0.489362 (-7135 1460);
DOT 1 (-2250 6200);
DOT 1 (-2825 6200);
DOT 1 (-2825 5775);
DOT 1 (-8350 2125);
DOT 1 (-8500 3325);
DOT 1 (-2125 2175);
DOT 1 (-2125 2125);
DOT 1 (-2125 2075);
DOT 1 (-2125 2325);
DOT 1 (-2125 2275);
DOT 1 (-2125 2425);
DOT 1 (-2125 2225);
DOT 1 (-2125 2375);
DOT 1 (-2125 2475);
DOT 1 (-2125 2625);
DOT 1 (-2125 2575);
DOT 1 (-2125 2525);
DOT 1 (-2125 2675);
DOT 1 (-2125 2725);
DOT 1 (-2125 2825);
DOT 1 (-2125 2775);
DOT 1 (-2125 2925);
DOT 1 (-2125 2975);
DOT 1 (-2125 2875);
DOT 1 (-2125 3125);
DOT 1 (-2125 3075);
DOT 1 (-2125 3025);
DOT 1 (-2125 3225);
DOT 1 (-2125 3175);
DOT 1 (-2125 3375);
DOT 1 (-2125 3325);
DOT 1 (-2125 3275);
DOT 1 (-2125 3475);
DOT 1 (-2125 3425);
DOT 1 (-2125 3625);
DOT 1 (-2125 3575);
DOT 1 (-2125 3525);
DOT 1 (-2125 3725);
DOT 1 (-2125 3675);
DOT 1 (-325 2175);
DOT 1 (-325 2075);
DOT 1 (-325 2025);
DOT 1 (-325 1975);
DOT 1 (-325 2325);
DOT 1 (-325 2275);
DOT 1 (-325 2225);
DOT 1 (-325 2425);
DOT 1 (-325 2375);
DOT 1 (-325 2475);
DOT 1 (-325 2625);
DOT 1 (-325 2575);
DOT 1 (-325 2525);
DOT 1 (-325 2675);
DOT 1 (-325 2725);
DOT 1 (-325 2825);
DOT 1 (-325 2775);
DOT 1 (-325 2925);
DOT 1 (-325 2975);
DOT 1 (-325 2875);
DOT 1 (-325 3175);
DOT 1 (-325 3075);
DOT 1 (-325 3025);
DOT 1 (-325 3225);
DOT 1 (-325 3125);
DOT 1 (-325 3425);
DOT 1 (-325 3325);
DOT 1 (-325 3275);
DOT 1 (-325 3475);
DOT 1 (-325 3375);
DOT 1 (-325 3625);
DOT 1 (-325 3575);
DOT 1 (-325 3525);
DOT 1 (-325 3725);
DOT 1 (-325 3675);
DOT 1 (-2125 3925);
DOT 1 (-2125 3825);
DOT 1 (-2125 3775);
DOT 1 (-2125 3975);
DOT 1 (-2125 3875);
DOT 1 (-2125 4125);
DOT 1 (-2125 4075);
DOT 1 (-2125 4025);
DOT 1 (-2125 4225);
DOT 1 (-2125 4175);
DOT 1 (-2125 4375);
DOT 1 (-2125 4325);
DOT 1 (-2125 4275);
DOT 1 (-2125 4475);
DOT 1 (-2125 4425);
DOT 1 (-2125 4525);
DOT 1 (-2125 4675);
DOT 1 (-2125 4625);
DOT 1 (-2125 4575);
DOT 1 (-2125 4725);
DOT 1 (-2125 4775);
DOT 1 (-2125 4875);
DOT 1 (-2125 4825);
DOT 1 (-2125 4975);
DOT 1 (-2125 5025);
DOT 1 (-2125 4925);
DOT 1 (-2125 5125);
DOT 1 (-2125 5075);
DOT 1 (-2125 5275);
DOT 1 (-2125 5325);
DOT 1 (-325 3875);
DOT 1 (-325 3825);
DOT 1 (-325 3775);
DOT 1 (-325 3975);
DOT 1 (-325 3925);
DOT 1 (-325 4125);
DOT 1 (-325 4075);
DOT 1 (-325 4025);
DOT 1 (-325 4225);
DOT 1 (-325 4375);
DOT 1 (-325 4275);
DOT 1 (-325 4325);
DOT 1 (-325 4475);
DOT 1 (-325 4425);
DOT 1 (-325 4525);
DOT 1 (-325 4675);
DOT 1 (-325 4625);
DOT 1 (-325 4575);
DOT 1 (-325 4725);
DOT 1 (-325 4775);
DOT 1 (-325 4875);
DOT 1 (-325 4825);
DOT 1 (-325 4975);
DOT 1 (-325 5025);
DOT 1 (-325 4925);
DOT 1 (-325 5225);
DOT 1 (-325 5125);
DOT 1 (-325 5075);
DOT 1 (-325 5275);
DOT 1 (-325 5175);
DOT 1 (-325 4175);
QUIT
